# Barreleye-G2_Tri-mode Expander-DVT-X01-SKU-BOM-X07-20171222_Final.xls.xlsx — PWA BOM (bom)
| FOXCONN TECHNOLOGY GROUP |  |  |  |  |  |  |  |  |  |  |  |  |  |  |  |  |  |  |  |  |  |  |  |
| BILL OF MATERIAL |  |  |  |  |  |  |  |  |  |  |  |  |  |  |  |  |  |  |  |  |  |  |  |
| REV OF  BOM | X07 | CUSTOMER |  | <name> |  | CUSTOMER P/N |  | PWA P/N： | PWA DESCRIPTION |  |  |  |  |  |  |  | PRODUCT CODE |  |  | PWA  REV | X01 | DATE | 43091 |
| Sourcing (Single/Sole/Multi) | Critical Commodity (Y or N) | Component Class (1, 2, other) | Customer PSL (Y or N) | Line Item | Item Number | Foxconn P/N | Customer P/N | Part Description | Manufacturer  Full Name | Manufacturer  Part Number | On-Board build status | SKU1 | SKU2 | SKU3 | Qty | RoHS Status | Location | CC Qual Build: | Qual by (Customer / ODM ?) | The Date of Change Part or Add 2nd Source | Configuration Identifier | Customer Comments | ODM Comments |
| Multi |  |  |  | 1 | 1 | 0101FGB00-000-G |  | PCB,Zaius-Tri-mode Expander DVT-X01,Blu,10L,9.134*5.118,G | GOLD CIRCUIT ELECTRONICS LTD. | 0101FGB00-000-G |  | 1 | 2 | 3 | 1 | G | PCB |  |  |  |  |  |  |
|  |  |  |  |  | 1 | 0101FGB00-000-G |  | PCB,Zaius-Tri-mode Expander DVT-X01,Blu,10L,9.134*5.118,G | ZHUHAI FOUNDER PRINTED CIRCUIT BOARD（HK） DEVELOPMENT LIMITED | 0101FGB00-000-G |  | 1 | 2 | 3 |  | G |  |  |  |  |  |  |  |
| Multi | Y |  | Y(4) | 2 | 2 | 62111EC00-021-G |  | ECAP,680uF,+/-20%,16V,105℃,G,SMD10*10,ESR<=80mOhm | NIPPON CHEMI-CON CORPORATION | EMZA160ADA681MJA0G | EVT | 1 |  |  | 2 | G | CE1,CE2 |  |  |  |  |  |  |
|  |  |  |  |  | 2 | 62110EH00-024-G |  | ECAP,680uF,+/-20%,16V,105_x0003_,G,SMD10X10.2,ESR<=80mOhm | PANASONIC INDUSTRIAL CO.,LTD. | EEEFK1C681P |  |  | 2 |  |  | G |  |  |  |  |  |  |  |
|  |  |  |  |  | 2 | 62111H200-018-G |  | ECAP,680uF,+/-20%,16V,105_x0003_,G,SMD10X10.5,ESR<=80mOhm | RUBYCON CORP. | 16TZV680M10X10.5 |  |  |  | 3 |  | G |  |  |  |  |  |  |  |
| Multi | Y | 2 | Y(3) | 3 | 3 | 620101T02-015-G | - | CAP,100nF,+/-10%,X7R,16V,G,SMD0402 | MURATA ELEC. NORTH AMERICA | GRM155R71C104K | EVT | 1 | 2 | 3 | 35 | G | PSCC1,C1,PFCC2,PELC2,PLTC5,C8,PSRC10,PLTC11,PELC11,PFCC13,PECC15,PECC16,PECC18,PECC19,C223,C225,C226,C229,C231,C393,C394,C395,C396,C397,C411,C413,C610,C611,C612,C968,C970,C1524,C2004,C2180,C2183 |  |  |  |  |  |  |
|  |  |  |  |  | 3 | 620101T00-012-G |  | CAP,100nF,+/-10%,X7R,16V,G,SMD0402 | WALSIN TECHNOLOGY CORPORATION | 0402B104K160CT |  | 1 | 2 | 3 |  | G |  |  |  |  |  |  |  |
|  |  |  |  |  | 3 | 620101T00-026-G |  | CAP,100nF,+/-10%,X7R,16V,G,SMD0402 | SAMSUNG SEMICONDUCTOR | CL05B104KO5NNNC |  | 1 | 2 | 3 |  | G |  |  |  |  |  |  |  |
|  |  |  |  |  | 3 | 620101T00-015-G |  | CAP,100nF,+/-10%,X7R,16V,G,SMD0402 | MURATA ELEC. NORTH AMERICA | GRM155R71C104KA88D |  | 1 | 2 | 3 |  | G |  |  |  |  |  |  |  |
| Multi | ND | ND | Y(1) | 4 | 4 | 62010BN00-015-G | - | CAP,1uF,+/-10%,X5R,6.3V,G,SMD0402 | MURATA ELEC. NORTH AMERICA | GRM155R60J105K |  | 1 | 2 | 3 | 3 | G | C2,C4,C5 |  |  |  |  |  |  |
|  |  |  |  |  | 4 | 62010BN00-011-G |  | CAP,1uF,+/-10%,X5R,6.3V,G,SMD0402 | YAGEO CORPORATION COMPONENT | CC0402KRX5R5BB105 | EVT | 1 | 2 | 3 |  | G |  |  |  |  |  |  |  |
|  |  |  |  |  | 4 | 62010BN00-012-G |  | CAP,1uF,+/-10%,X5R,6.3V,G,SMD0402 | WALSIN TECHNOLOGY CORPORATION | 0402X105K6R3CT |  | 1 | 2 | 3 |  | G |  |  |  |  |  |  |  |
|  |  |  |  |  | 4 | 62010BN00-026-G |  | CAP,1uF,+/-10%,X5R,6.3V,G,SMD0402 | SAMSUNG SEMICONDUCTOR | CL05A105KQ5NNNC |  | 1 | 2 | 3 |  | G |  |  |  |  |  |  |  |
|  |  |  |  |  | 4 | 62010BN00-023-G |  | CAP,1uF,+/-10%,X5R,6.3V,G,SMD0402 | TAIYO ELECTRIC IND.CO.LTD | JMK105BJ105KV |  | 1 | 2 | 3 |  | G |  |  |  |  |  |  |  |
| Multi | ND | ND | Y(3) | 5 | 5 | 620106200-015-G | - | CAP,10nF,+/-10%,X7R,16V,G,SMD0402 | MURATA ELEC. NORTH AMERICA | GRM155R71C103K |  | 1 | 2 | 3 | 33 | G | C3,C6,C7,C25,C30,C39,C44,C49,C54,C61,C62,C69,C70,C77,C78,C85,C86,C93,C94,C101,C102,C109,C110,C117,C118,C125,C126,C133,C134,C141,C142,C149,C150 |  |  |  |  |  |  |
|  |  |  |  |  | 5 | 620106200-012-G |  | CAP,10nF,+/-10%,X7R,16V,G,SMD0402 | WALSIN TECHNOLOGY CORPORATION | 0402B103K160CT |  | 1 | 2 | 3 |  | G |  |  |  |  |  |  |  |
|  |  |  |  |  | 5 | 620106200-026-G |  | CAP,10nF,+/-10%,X7R,16V,G,SMD0402 | SAMSUNG SEMICONDUCTOR | CL05B103KO5NNNC | EVT | 1 | 2 | 3 |  | G |  |  |  |  |  |  |  |
|  |  |  |  |  | 5 | 620106200-023-G |  | CAP,10nF,+/-10%,X7R,16V,G,SMD0402 | TAIYO ELECTRIC IND.CO.LTD | EMK105B7103KV-F |  | 1 | 2 | 3 |  | G |  |  |  |  |  |  |  |
| Multi | Y | 2 | Y(1) | 6 | 6 | 620108H00-015-G | - | CAP,22uF,+/-20%,X5R,6.3V,G,SMD0805 | MURATA ELEC. NORTH AMERICA | GRM21BR60J226M |  | 1 | 2 | 3 | 10 | G | C9,C13,C17,C21,C26,C31,C35,C40,C45,C50 |  |  |  |  |  |  |
|  |  |  |  |  | 6 | 620108H04-023-G |  | CAP,22uF,+/-20%,X5R,6.3V,G,SMD0805 | TAIYO ELECTRIC IND.CO.LTD | JMK212BJ226MG-T |  | 1 | 2 | 3 |  | G |  |  |  |  |  |  |  |
|  |  |  |  |  | 6 | 620108H00-026-G |  | CAP,22uF,+/-20%,X5R,6.3V,G,SMD0805 | SAMSUNG SEMICONDUCTOR | CL21A226MQQNNNE | EVT | 1 | 2 | 3 |  | G |  |  |  |  |  |  |  |
|  |  |  |  |  | 6 | 620108H00-011-G |  | CAP,22uF,+/-20%,X5R,6.3V,G,SMD0805 | YAGEO CORPORATION COMPONENT | CC0805MKX5R5BB226 | EVT | 1 | 2 | 3 |  | G |  |  |  |  |  |  |  |
| Multi | ND | ND | Y(1) | 7 | 7 | 62010L000-015-G | - | CAP,10uF,+/-20%,X5R,6.3V,G,SMD0603 | MURATA ELEC. NORTH AMERICA | GRM188R60J106M | EVT | 1 | 2 | 3 | 23 | G | C10,C14,C18,C22,C27,C32,C36,C41,C46,C51,C151,C152,C153,C154,C155,C191,C192,C193,C194,C224,C227,C228,C230 |  |  |  |  |  |  |
|  |  |  |  |  | 7 | 62010L000-023-G |  | CAP,10uF,+/-20%,X5R,6.3V,G,SMD0603 | TAIYO ELECTRIC IND.CO.LTD | JMK107BJ106MA-T |  | 1 | 2 | 3 |  | G |  |  |  |  |  |  |  |
|  |  |  |  |  | 7 | 62010L000-012-G |  | CAP,10uF,+/-20%,X5R,6.3V,G,SMD0603 | WALSIN TECHNOLOGY CORPORATION | 0603X106M6R3CT |  | 1 | 2 | 3 |  | G |  |  |  |  |  |  |  |
|  |  |  |  |  | 7 | 62010L000-026-G |  | CAP,10uF,+/-20%,X5R,6.3V,G,SMD0603 | SAMSUNG SEMICONDUCTOR | CL10A106MQ8NNNC |  | 1 | 2 | 3 |  | G |  |  |  |  |  |  |  |
|  |  |  |  |  | 7 | 62010L000-011-G |  | CAP,10uF,+/-20%,X5R,6.3V,G,SMD0603 | YAGEO CORPORATION COMPONENT | CC0603MRX5R5BB106 |  | 1 | 2 | 3 |  | G |  |  |  |  |  |  |  |
| Multi | ND | ND | N | 8 | 8 | 62012NU00-015-G | - | CAP,1uF,+/-10%,X7R,6.3V,G,SMD0402 | MURATA ELEC. NORTH AMERICA | GRM155R70J105KA12D | EVT | 1 | 2 | 3 | 22 | G | C11,C15,C19,C23,C28,C33,C37,C42,C47,C52,C57,C65,C73,C81,C89,C97,C105,C113,C121,C129,C137,C145 |  |  |  |  |  |  |
|  |  |  |  |  | 8 | 62012NU00-026-G |  | CAP,1uF,+/-10%,X7R,6.3V,G,SMD0402 | SAMSUNG SEMICONDUCTOR | CL05B105KQ5NQNC |  | 1 | 2 | 3 |  | G |  |  |  |  |  |  |  |
| Multi | ND | ND | Y(3) | 9 | 9 | 620103700-015-G | - | CAP,100nF,+/-10%,X7R,10V,G,SMD0402 | MURATA ELEC. NORTH AMERICA | GRM155R71A104K |  | 1 | 2 | 3 | 106 | G | PSLC10,PSGC10,C12,C16,C20,C24,C29,C34,C38,C43,C48,C53,C58,C59,C60,C66,C67,C68,C74,C75,C76,C82,C83,C84,C90,C91,C92,C98,C99,C100,C106,C107,C108,C114,C115,C116,C122,C123,C124,C130,C131,C132,C138,C139,C140,C146,C147,C148,C161,C162,C163,C164,C165,C166,C167,C168,C169,C170,C171,C172,C173,C174,C175,C176,C177,C178,C179,C180,C181,C182,C183,C184,C185,C186,C187,C188,C189,C190,C199,C200,C201,C202,C203,C204,C205,C206,C207,C208,C209,C210,C211,C212,C213,C214,C215,C216,C217,C218,C219,C220,C221,C222,C415,C2179,C2181,C2182 |  |  |  |  |  |  |
|  |  |  |  |  | 9 | 620103700-012-G |  | CAP,0.1uF,+/-10%,X7R,10V,G,SMD0402 | WALSIN TECHNOLOGY CORPORATION | 0402B104K100CT | EVT | 1 | 2 | 3 |  | G |  |  |  |  |  |  |  |
|  |  |  |  |  | 9 | 620103700-023-G |  | CAP,100nF,+/-10%,X7R,10V,G,SMD0402 | TAIYO ELECTRIC IND.CO.LTD | LMK105B7104KV-F |  | 1 | 2 | 3 |  | G |  |  |  |  |  |  |  |
|  |  |  |  |  | 9 | 620103700-026-G |  | CAP,100nF,+/-10%,X7R,10V,G,SMD0402 | SAMSUNG SEMICONDUCTOR | CL05B104KP5NNNC |  | 1 | 2 | 3 |  | G |  |  |  |  |  |  |  |
| Multi | ND |  | Y(1) | 10 | 10 | 620132700-015-G |  | CAP,100uF,+/-20%,X5R,6.3V,G,SMD0805 | MURATA ELEC. NORTH AMERICA | GRM21BR60J107ME15L | EVT | 1 | 2 | 3 | 12 | G | C55,C63,C71,C79,C87,C95,C103,C111,C119,C127,C135,C143 |  |  |  |  |  |  |
|  |  |  |  |  | 10 | 620132700-012-G |  | CAP,100uF,+/-20%,X5R,6.3V,G,SMD0805 | WALSIN TECHNOLOGY CORPORATION | 0805X107M6R3CT |  | 1 | 2 | 3 |  | G |  |  |  |  |  |  |  |
| Multi | ND |  | Y(1) | 11 | 11 | 62012Y400-015-G |  | CAP,22uF,+/-20%,X5R,6.3V,G,SMD0402 | MURATA ELEC. NORTH AMERICA | GRM155R60J226ME11D | EVT | 1 | 2 | 3 | 12 | G | C56,C64,C72,C80,C88,C96,C104,C112,C120,C128,C136,C144 |  |  |  |  |  |  |
|  |  |  |  |  | 11 | 62012Y400-026-G |  | CAP,22uF,+/-20%,X5R,6.3V,G,SMD0402 | SAMSUNG SEMICONDUCTOR | CL05A226MQ5N6J8 |  | 1 | 2 | 3 |  | G |  |  |  |  |  |  |  |
|  |  |  |  |  | 11 | 62012Y400-011-G |  | CAP,22uF,+/-20%,X5R,6.3V,G,SMD0402 | YAGEO CORPORATION COMPONENT | CC0402MRX5R5BB226 |  | 1 | 2 | 3 |  | G |  |  |  |  |  |  |  |
|  |  |  |  |  | 11 | 62012Y400-012-G |  | CAP,22uF,+/-20%,X5R,6.3V,G,SMD0402 | WALSIN TECHNOLOGY CORPORATION | 0402X226M6R3CT |  | 1 | 2 | 3 |  | G |  |  |  |  |  |  |  |
| Multi | ND | ND | Y(1) | 12 | 12 | 62010P501-015-G | - | CAP,1nF,+/-10%,X7R,16V,G,SMD0402 | MURATA ELEC. NORTH AMERICA | GRM155R71C102KA01D |  | 1 | 2 | 3 | 9 | G | C156,C157,C158,C159,C160,C195,C196,C197,C198 |  |  |  |  |  |  |
|  |  |  |  |  | 12 | 62010P500-023-G |  | CAP,1nF,+/-10%,X7R,16V,G,SMD0402 | TAIYO ELECTRIC IND.CO.LTD | EMK105B7102KV-F | EVT | 1 | 2 | 3 |  | G |  |  |  |  |  |  |  |
|  |  |  |  |  | 12 | 62010P500-026-G |  | CAP,1nF,+/-10%,X7R,16V,G,SMD0402 | SAMSUNG SEMICONDUCTOR | CL05B102KO5NNNC |  | 1 | 2 | 3 |  | G |  |  |  |  |  |  |  |
| Multi | ND |  | Y(2) | 13 | 13 | 62012QF00-023-G |  | CAP,10nF,+/-10%,X7R,16V,G,SMD0201 | TAIYO ELECTRIC IND.CO.LTD | EMK063B7103KP-F | EVT | 1 | 2 | 3 | 212 | G | C233,C234,C235,C236,C237,C238,C239,C240,C241,C242,C243,C244,C245,C246,C247,C248,C249,C250,C251,C252,C253,C254,C255,C256,C257,C258,C259,C260,C261,C262,C263,C264,C297,C298,C299,C300,C301,C302,C303,C304,C305,C306,C307,C308,C309,C310,C311,C312,C313,C314,C315,C316,C317,C318,C319,C320,C321,C322,C323,C324,C325,C326,C327,C328,C329,C330,C331,C332,C333,C334,C335,C336,C337,C338,C339,C340,C341,C342,C343,C344,C345,C346,C347,C348,C349,C350,C351,C352,C353,C354,C355,C356,C357,C358,C359,C360,C361,C362,C363,C364,C365,C366,C367,C368,C369,C370,C371,C372,C373,C374,C375,C376,C377,C378,C379,C380,C381,C382,C383,C384,C385,C386,C387,C388,C389,C390,C391,C392,C640,C641,C642,C643,C644,C645,C646,C647,C648,C649,C650,C651,C652,C653,C654,C655,C656,C657,C658,C659,C660,C661,C662,C663,C664,C665,C674,C675,C676,C677,C678,C679,C680,C681,C682,C725,C726,C727,C728,C729,C730,C731,C732,C733,C734,C735,C736,C737,C738,C739,C740,C741,C742,C743,C744,C745,C746,C747,C748,C749,C750,C751,C752,C753,C754,C755,C756,C757,C758,C759,C775,C776,C777,C778,C779,C780,C781,C797,C798,C799,C800,C801,C802,C803 |  |  |  |  |  |  |
|  |  |  |  |  | 13 | 62012QF00-012-G |  | CAP,10nF,+/-10%,X7R,16V,G,SMD0201 | WALSIN TECHNOLOGY CORPORATION | 0201B103K160CT |  | 1 | 2 | 3 |  | G |  |  |  |  |  |  |  |
|  |  |  |  |  | 13 | 62012QF00-026-G |  | CAP,10nF,+/-10%,X7R,16V,G,SMD0201 | SAMSUNG SEMICONDUCTOR | CL03B103KO3NNNC |  | 1 | 2 | 3 |  | G |  |  |  |  |  |  |  |
| Multi | N | ND | Y(3) | 14 | 14 | 62012GG00-015-G | - | CAP,10uF,+/-10%,X7S,25V,G,SMD0805 | MURATA ELEC. NORTH AMERICA | GRM21BC71E106K | EVT | 1 | 2 | 3 | 7 | G | PLTC1,PSRC3,PSLC3,PSGC3,C398,C399,PSCC3004 |  |  |  |  |  |  |
|  |  |  |  |  | 14 | 62012GG00-012-G |  | CAP,10uF,+/-10%,X7S,25V,G,SMD0805 | WALSIN TECHNOLOGY CORPORATION | 0805A106K250CT |  | 1 | 2 | 3 |  | G |  |  |  |  |  |  |  |
| Multi | ND | ND | Y(1) | 15 | 15 | 62012A400-015-G | - | CAP,100nF,+/-10%,X7R,25V,G,SMD0402 | MURATA ELEC. NORTH AMERICA | GRM155R71E104KE14D | EVT | 1 | 2 | 3 | 17 | G | PSRC1,PSLC1,PSGC1,PELC3,PLTC4,PFCC4,PELC4,PSRC6,PSLC6,PSGC6,PELC10,PFCC11,PECC13,C400,C404,PSCC3002,PSCC3008 |  |  |  |  |  |  |
|  |  |  |  |  | 15 | 62012A400-023-G |  | CAP,100nF,+/-10%,X7R,25V,G,SMD0402 | TAIYO ELECTRIC IND.CO.LTD | TMK105B7104KV-FR |  | 1 | 2 | 3 |  | G |  |  |  |  |  |  |  |
|  |  |  |  |  | 15 | 62012A400-026-G |  | CAP,100nF,+/-10%,X7R,25V,G,SMD0402 | SAMSUNG SEMICONDUCTOR | CL05B104KA5NNNC |  | 1 | 2 | 3 |  | G |  |  |  |  |  |  |  |
|  |  |  |  |  | 15 | 62012A400-012-G |  | CAP,100nF,+/-10%,X7R,25V,G,SMD0402 | WALSIN TECHNOLOGY CORPORATION | 0402B104K250CT |  | 1 | 2 | 3 |  | G |  |  |  |  |  |  |  |
| Multi | ND |  | N | 16 | 16 | 620109N00-015-G |  | CAP,2.2uF,+/-10%,X7R,10V,G,SMD0603 | MURATA ELEC. NORTH AMERICA | GRM188R71A225K | EVT | 1 | 2 | 3 | 1 | G | C401 |  |  |  |  |  |  |
|  |  |  |  |  | 16 | 620109N00-023-G |  | CAP,2.2uF,+/-10%,X7R,10V,G,SMD0603 | TAIYO ELECTRIC IND.CO.LTD | LMK107B7225KA-T |  | 1 | 2 | 3 |  | G |  |  |  |  |  |  |  |
|  |  |  |  |  | 16 | 620109N00-026-G |  | CAP,2.2uF,+/-10%,X7R,10V,G,SMD0603 | SAMSUNG SEMICONDUCTOR | CL10B225KP8NNNC |  | 1 | 2 | 3 |  | G |  |  |  |  |  |  |  |
| Multi | N | ND | Y(3) | 17 | 17 | 62012H100-015-G | - | CAP,10uF,+/-20%,X6S,10V,G,SMD0603 | MURATA ELEC. NORTH AMERICA | GRM188C81A106M | EVT | 1 | 2 | 3 | 3 | G | PSRC16,C402,C403 |  |  |  |  |  |  |
|  |  |  |  |  | 17 | 62012H100-023-G |  | CAP,10uF,+/-20%,X6S,10V,G,SMD0603 | TAIYO ELECTRIC IND.CO.LTD | LMK107BC6106MA-T |  | 1 | 2 | 3 |  | G |  |  |  |  |  |  |  |
|  |  |  |  |  | 17 | 62012H100-026-G |  | CAP,10uF,+/-20%,X6S,10V,G,SMD0603 | SAMSUNG SEMICONDUCTOR | CL10X106MP8NRNC |  | 1 | 2 | 3 |  | G |  |  |  |  |  |  |  |
| Multi | ND | ND | Y(1) | 18 | 18 | 620108J00-015-G | - | CAP,100uF,+/-20%,X5R,6.3V,G,SMD1210 | MURATA ELEC. NORTH AMERICA | GRM32ER60J107M | EVT | 1 | 2 | 3 | 1 | G | C406 |  |  |  |  |  |  |
|  |  |  |  |  | 18 | 620108J00-012-G |  | CAP,100uF,+/-20%,X5R,6.3V,G,SMD1210 | WALSIN TECHNOLOGY CORPORATION | 1210X107M6R3CT |  | 1 | 2 | 3 |  | G |  |  |  |  |  |  |  |
|  |  |  |  |  | 18 | 620108J00-011-G |  | CAP,100uF,+/-20%,X5R,6.3V,G,SMD1210 | YAGEO CORPORATION COMPONENT | CC1210MKX5R5BB107 |  | 1 | 2 | 3 |  | G |  |  |  |  |  |  |  |
|  |  |  |  |  | 18 | 620108J00-026-G |  | CAP,100uF,+/-20%,X5R,6.3V,G,SMD1210 | SAMSUNG SEMICONDUCTOR | CL32A107MQVNNNE |  | 1 | 2 | 3 |  | G |  |  |  |  |  |  |  |
|  |  |  |  |  | 18 | 620108J07-023-G |  | CAP,100uF,+/-20%,X5R,6.3V,G,SMD1210 | TAIYO ELECTRIC IND.CO.LTD | JMK325ABJ107MM-T |  | 1 | 2 | 3 |  | G |  |  |  |  |  |  |  |
| Multi | Y | 2 | Y(1) | 19 | 19 | 620100A00-015-G | - | CAP,10uF,+/-10%,X5R,16V,G,SMD1206 | MURATA ELEC. NORTH AMERICA | GRM31CR61C106K |  | 1 | 2 | 3 | 8 | G | C409,C410,C412,C414,C966,C967,C969,C971 |  |  |  |  |  |  |
|  |  |  |  |  | 19 | 620100A00-026-G |  | CAP,10uF,+/-10%,X5R,16V,G,SMD1206 | SAMSUNG SEMICONDUCTOR | CL31A106KOHNNNE | EVT | 1 | 2 | 3 |  | G |  |  |  |  |  |  |  |
|  |  |  |  |  | 19 | 620100A03-023-G |  | CAP,10uF,+/-10%,X5R,16V,G,SMD1206 | TAIYO ELECTRIC IND.CO.LTD | EMK316BJ106KL-T |  | 1 | 2 | 3 |  | G |  |  |  |  |  |  |  |
|  |  |  |  |  | 19 | 620100A00-012-G |  | CAP,10uF,+/-10%,X5R,16V,G,SMD1206 | WALSIN TECHNOLOGY CORPORATION | 1206X106K160CT |  | 1 | 2 | 3 |  | G |  |  |  |  |  |  |  |
|  |  |  |  |  | 19 | 620100A00-011-G |  | CAP,10uF,+/-10%,X5R,16V,G,SMD1206 | YAGEO CORPORATION COMPONENT | CC1206KKX5R7BB106 |  | 1 | 2 | 3 |  | G |  |  |  |  |  |  |  |
| Multi | Y | 2 | Y(3) | 20 | 20 | 62011DF01-015-G | - | CAP,220nF,+/-10%,X7R,16V,G,SMD0402 | MURATA ELEC. NORTH AMERICA | GRM155R71C224K | EVT | 1 | 2 | 3 | 288 | G | C416,C417,C418,C419,C420,C421,C422,C423,C424,C425,C426,C427,C428,C429,C430,C431,C432,C433,C434,C435,C436,C437,C438,C439,C440,C441,C442,C443,C444,C445,C446,C447,C448,C449,C450,C451,C452,C453,C454,C455,C456,C457,C458,C459,C460,C461,C462,C463,C464,C465,C466,C467,C468,C469,C470,C471,C472,C473,C474,C475,C476,C477,C478,C479,C480,C481,C482,C485,C488,C489,C490,C491,C496,C497,C498,C499,C504,C505,C506,C507,C512,C513,C514,C515,C516,C517,C518,C519,C520,C521,C522,C523,C524,C525,C526,C527,C528,C529,C530,C531,C532,C533,C534,C535,C536,C537,C538,C539,C540,C541,C542,C543,C544,C545,C550,C551,C552,C553,C554,C555,C560,C561,C562,C563,C568,C569,C570,C571,C576,C577,C578,C582,C584,C585,C586,C587,C592,C593,C594,C595,C600,C601,C602,C603,C822,C823,C824,C825,C826,C827,C828,C829,C830,C831,C832,C833,C834,C835,C836,C837,C838,C839,C840,C841,C842,C843,C844,C845,C846,C847,C848,C849,C850,C851,C852,C853,C854,C855,C856,C857,C858,C859,C860,C862,C863,C864,C865,C866,C867,C868,C869,C870,C871,C872,C873,C874,C875,C876,C877,C878,C879,C880,C881,C882,C883,C884,C885,C886,C887,C888,C889,C890,C891,C892,C893,C894,C895,C896,C897,C898,C899,C900,C901,C910,C911,C912,C913,C914,C915,C916,C917,C918,C919,C920,C921,C922,C923,C924,C925,C926,C927,C928,C929,C930,C931,C932,C933,C934,C935,C936,C937,C938,C939,C940,C941,C942,C943,C944,C945,C946,C947,C948,C949,C950,C951,C952,C953,C954,C955,C956,C957,C958,C959,C960,C961,C962,C963,C964,C965,C2115,C2136,C2138,C2141,C2142,C2144,C2145,C2146,C2166 |  |  |  |  |  |  |
|  |  |  |  |  | 20 | 62011DF00-026-G |  | CAP,220nF,+/-10%,X7R,16V,G,SMD0402 | SAMSUNG SEMICONDUCTOR | CL05B224KO5NNNC |  | 1 | 2 | 3 |  | G |  |  |  |  |  |  |  |
|  |  |  |  |  | 20 | 62011DF00-023-G |  | CAP,220nF,+/-10%,X7R,16V,G,SMD0402 | TAIYO ELECTRIC IND.CO.LTD | EMK105B7224KV-FR |  | 1 | 2 | 3 |  | G |  |  |  |  |  |  |  |
| Multi | Y | ND | Y(1) | 21 | 21 | 620119R04-015-G | - | CAP,22uF,+/-20%,X6S,4V,G,SMD0805 | MURATA ELEC. NORTH AMERICA | GRM21BC80G226M | EVT | 1 | 2 | 3 | 35 | G | PSLC7,PSGC7,PSLC8,PSGC8,PSLC11,PSGC11,PSLC12,PSGC12,PFCC14,PSLC15,PSGC15,PFCC15,PFCC16,PFCC17,PFCC18,PFCC20,PFCC21,PFCC22,PFCC23,PFCC24,PFCC25,PFCC26,PFCC27,PFCC28,PFCC29,PECC29,PFCC30,PECC30,PFCC31,PFCC32,PFCC33,PFCC34,PECC40,PECC41,C609 |  |  |  |  |  |  |
|  |  |  |  |  | 21 | 620119R01-015-G |  | CAP,22uF,+/-20%,X6S,4V,G,SMD0805 | MURATA ELEC. NORTH AMERICA | GRM21BC80G226ME39K |  | 1 | 2 | 3 |  | G |  |  |  |  |  |  |  |
|  |  |  |  |  | 21 | 620119R00-023-G |  | CAP,22uF,+/-20%,X6S,4V,G,SMD0805 | TAIYO ELECTRIC IND.CO.LTD | AMK212C6226MG-T |  | 1 | 2 | 3 |  | G |  |  |  |  |  |  |  |
|  |  |  |  |  | 21 | 620119R00-026-G |  | CAP,22uF,+/-20%,X6S,4V,G,SMD0805 | SAMSUNG SEMICONDUCTOR | CL21X226MRQNNNE |  | 1 | 2 | 3 |  | G |  |  |  |  |  |  |  |
| Multi | ND | ND | Y(3) | 22 | 22 | 62012C800-015-G | - | CAP,100nF,+/-10%,X5R,16V,G,SMD0201 | MURATA ELEC. NORTH AMERICA | GRM033R61C104K | EVT | 1 | 2 | 3 | 82 | G | C614,C615,C616,C617,C618,C619,C620,C621,C622,C623,C624,C625,C626,C627,C628,C629,C630,C631,C632,C633,C634,C635,C636,C637,C638,C639,C666,C667,C668,C669,C670,C671,C672,C673,C691,C692,C693,C694,C695,C696,C697,C698,C699,C700,C701,C702,C703,C704,C705,C706,C707,C708,C709,C710,C711,C712,C713,C714,C715,C716,C717,C718,C719,C720,C721,C722,C723,C724,C768,C769,C770,C771,C772,C773,C774,C790,C791,C792,C793,C794,C795,C796 |  |  |  |  |  |  |
|  |  |  |  |  | 22 | 62012C800-023-G |  | CAP,100nF,+/-10%,X5R,16V,G,SMD0201 | TAIYO ELECTRIC IND.CO.LTD | EMK063BJ104KP-F |  | 1 | 2 | 3 |  | G |  |  |  |  |  |  |  |
|  |  |  |  |  | 22 | 62012C800-026-G |  | CAP,100nF,+/-10%,X5R,16V,G,SMD0201 | SAMSUNG SEMICONDUCTOR | CL03A104KO3NNNC |  | 1 | 2 | 3 |  | G |  |  |  |  |  |  |  |
|  |  |  |  |  | 22 | 62012C800-011-G |  | CAP,100nF,+/-10%,X5R,16V,G,SMD0201 | YAGEO CORPORATION COMPONENT | CC0201KRX5R7BB104 |  | 1 | 2 | 3 |  | G |  |  |  |  |  |  |  |
| Multi | Y | 2 | Y(1) | 23 | 23 | 620105400-015-G |  | CAP,1uF,+/-10%,X7R,16V,G,SMD0603 | MURATA ELEC. NORTH AMERICA | GRM188R71C105K | EVT | 1 | 2 | 3 | 25 | G | PFCC12,C683,C684,C685,C686,C687,C688,C689,C690,C760,C761,C762,C763,C764,C765,C766,C767,C782,C783,C784,C785,C786,C787,C788,C789 |  |  |  |  |  |  |
|  |  |  |  |  | 23 | 620105400-012-G |  | CAP,1uF,+/-10%,X7R,16V,G,SMD0603 | WALSIN TECHNOLOGY CORPORATION | 0603B105K160CT | EVT | 1 | 2 | 3 |  | G |  |  |  |  |  |  |  |
|  |  |  |  |  | 23 | 620105400-011-G |  | CAP,1uF,+/-10%,X7R,16V,G,SMD0603 | YAGEO CORPORATION COMPONENT | CC0603KRX7R7BB105 |  | 1 | 2 | 3 |  | G |  |  |  |  |  |  |  |
|  |  |  |  |  | 23 | 620105400-026-G |  | CAP,1uF,+/-10%,X7R,16V,G,SMD0603 | SAMSUNG SEMICONDUCTOR | CL10B105KO8NNNC |  | 1 | 2 | 3 |  | G |  |  |  |  |  |  |  |
|  |  |  |  |  | 23 | 620105400-023-G |  | CAP,1uF,+/-10%,X7R,16V,G,SMD0603 | TAIYO ELECTRIC IND.CO.LTD | EMK107B7105KA-T |  | 1 | 2 | 3 |  | G |  |  |  |  |  |  |  |
| Multi | ND | ND | Y(3) | 24 | 24 | 620100L00-015-G | - | CAP,22pF,+/-5%,NPO(C0G),50V,G,SMD0402 | MURATA ELEC. NORTH AMERICA | GRM1555C1H220J | EVT | 1 | 2 | 3 | 2 | G | C806,C807 |  |  |  |  |  |  |
|  |  |  |  |  | 24 | 620100L08-012-G |  | CAP,22pF,+/-5%,NPO(C0G),50V,G,SMD0402 | WALSIN TECHNOLOGY CORPORATION | 0402N220J500CT |  | 1 | 2 | 3 |  | G |  |  |  |  |  |  |  |
|  |  |  |  |  | 24 | 620100L00-023-G |  | CAP,22pF,+/-5%,NPO(C0G),50V,G,SMD0402 | TAIYO ELECTRIC IND.CO.LTD | UMK105CG220JV-F |  | 1 | 2 | 3 |  | G |  |  |  |  |  |  |  |
|  |  |  |  |  | 24 | 620100L00-026-G |  | CAP,22pF,+/-5%,NPO(C0G),50V,G,SMD0402 | SAMSUNG SEMICONDUCTOR | CL05C220JB5NNNC |  | 1 | 2 | 3 |  | G |  |  |  |  |  |  |  |
| Multi | ND | ND | Y(3) | 25 | 25 | 620102U00-015-G | - | CAP,100nF,+/-10%,X5R,10V,G,SMD0402 | MURATA ELEC. NORTH AMERICA | GRM155R61A104K | EVT | 1 | 2 | 3 | 3 | G | C808,C2171,C2173 |  |  |  |  |  |  |
|  |  |  |  |  | 25 | 620102U00-023-G |  | CAP,100nF,+/-10%,X5R,10V,G,SMD0402 | TAIYO ELECTRIC IND.CO.LTD | LMK105BJ104KV-F |  | 1 | 2 | 3 |  | G |  |  |  |  |  |  |  |
|  |  |  |  |  | 25 | 620102U00-011-G |  | CAP,100nF,+/-10%,X5R,10V,G,SMD0402 | YAGEO CORPORATION COMPONENT | CC0402KRX5R6BB104 |  | 1 | 2 | 3 |  | G |  |  |  |  |  |  |  |
|  |  |  |  |  | 25 | 620102U00-026-G |  | CAP,100nF,+/-10%,X5R,10V,G,SMD0402 | SAMSUNG SEMICONDUCTOR | CL05A104KP5NNNC |  | 1 | 2 | 3 |  | G |  |  |  |  |  |  |  |
|  |  |  |  |  | 25 | 620102U00-012-G |  | CAP,100nF,+/-10%,X5R,10V,G,SMD0402 | WALSIN TECHNOLOGY CORPORATION | 0402X104K100CT |  | 1 | 2 | 3 |  | G |  |  |  |  |  |  |  |
| Multi | ND |  | Y(1) | 26 | 26 | 62011CA01-015-G |  | CAP,10uF,+/-10%,X5R,10V,G,SMD0603 | MURATA ELEC. NORTH AMERICA | GRM188R61A106K | EVT | 1 | 2 | 3 | 1 | G | C2170 |  |  |  |  |  |  |
|  |  |  |  |  | 26 | 62011CA00-026-G |  | CAP,10uF,+/-10%,X5R,10V,G,SMD0603 | SAMSUNG SEMICONDUCTOR | CL10A106KP8NNNC |  | 1 | 2 | 3 |  | G |  |  |  |  |  |  |  |
|  |  |  |  |  | 26 | 62011CA00-011-G |  | CAP,10uF,+/-10%,X5R,10V,G,SMD0603 | YAGEO CORPORATION COMPONENT | CC0603KRX5R6BB106 |  | 1 | 2 | 3 |  | G |  |  |  |  |  |  |  |
|  |  |  |  |  | 26 | 62011CA00-012-G |  | CAP,10uF,+/-10%,X5R,10V,G,SMD0603 | WALSIN TECHNOLOGY CORPORATION | 0603X106K100CT |  | 1 | 2 | 3 |  | G |  |  |  |  |  |  |  |
| Multi | Y | 2 | Y(1) | 27 | 27 | 62010JJ00-015-G | - | CAP,1uF,+/-10%,X5R,10V,G,SMD0402 | MURATA ELEC. NORTH AMERICA | GRM155R61A105K | EVT | 1 | 2 | 3 | 2 | G | PECC8,C2172 |  |  |  |  |  |  |
|  |  |  |  |  | 27 | 62010JJ01-023-G |  | CAP,1uF,+/-10%,X5R,10V,G,SMD0402 | TAIYO ELECTRIC IND.CO.LTD | LMK105BJ105KV-F |  | 1 | 2 | 3 |  | G |  |  |  |  |  |  |  |
|  |  |  |  |  | 27 | 62010JJ00-011-G |  | CAP,1uF,+/-10%,X5R,10V,G,SMD0402 | YAGEO CORPORATION COMPONENT | CC0402KRX5R6BB105 |  | 1 | 2 | 3 |  | G |  |  |  |  |  |  |  |
|  |  |  |  |  | 27 | 62010JJ00-012-G |  | CAP,1uF,+/-10%,X5R,10V,G,SMD0402 | WALSIN TECHNOLOGY CORPORATION | 0402X105K100CT |  | 1 | 2 | 3 |  | G |  |  |  |  |  |  |  |
|  |  |  |  |  | 27 | 62010JJ00-026-G |  | CAP,1uF,+/-10%,X5R,10V,G,SMD0402 | SAMSUNG SEMICONDUCTOR | CL05A105KP5NNNC |  | 1 | 2 | 3 |  | G |  |  |  |  |  |  |  |
| Single | Y | 2 | N | 28 | 28 | 520308900-214-G | - | DIODE,Schottky,BAR43FILM,30V,0.1A,G,SOT23-3,SMD | ST MICRO ELECTRONICS,INC | BAR43FILM | EVT | 1 | 2 | 3 | 7 | G | D1,D2,D3,D4,D5,D6,D7 |  |  |  |  |  |  |
| Single | Y | 1 | N | 29 | 29 | 521107T00-289-G | KX549 | LED,Gre,LTST-C190KGKT,2.4V,30mA,G,SMD0603 | LITE-ON TECHNOLOGY CORPORATION | LTST-C190KGKT | EVT | 1 | 2 | 3 | 29 | G | LED_HB1,LED_BLK1,LED_SASEXP_P0V9,LED_SW1_P0,LED_SW1_P1,LED_SW1_P2,LED_SW1_P3,LED_SW1_P4,LED_SW1_P5,LED_SW1_P6,LED_SW1_P7,LED_SW1_P8,LED_SW1_P9,LED_SW1_P10,LED_SW1_P11,LED_SW1_P12,LED_SW1_P13,LED_SW1_P14,LED_SW1_P15,LED_SW1_P16,LED_SW1_P17,LED_SW1_P18,LED_SW1_P19,LED_SW1_P20,LED_SW1_P21,LED_SW1_P22,LED_SW1_P23,LED_PEX9797_PG,LED_EXP_BP_PG |  |  |  |  |  |  |
| Multi | N | Other | N | 30 | 30 | 72010KB01-016-G | - | FB,330 Ohm@100MHz,+/-25%,2.5A,50mOhm,G,SMD0805 | TDK ELECTRONICS EUROPE GMBH | MPZ2012S331AT |  |  | 2 |  | 1 | G | L1 |  |  |  |  |  |  |
|  |  |  |  |  | 30 | 720100W00-015-G |  | FB,330 Ohm@100MHz,+/-25%,1.5A,90mOhm,G,SMD0805 | MURATA ELEC. NORTH AMERICA | BLM21PG331SN1D | EVT | 1 |  | 3 |  | G |  |  |  |  |  |  |  |
|  |  |  |  |  | 30 | 720104R00-023-G |  | FB,330 Ohm@100MHz,+/-25%,1.8A,80mOhm,G,SMD0805 | TAIYO ELECTRIC IND.CO.LTD | FBMH2012HM331-T |  |  |  |  |  | G |  |  |  |  |  |  |  |
| Multi | ND | ND | N | 31 | 31 | 720103500-016-G |  | FB,600 Ohm@100MHz,+/-25%,2A,100mOhm,G,SMD0805 | TDK ELECTRONICS EUROPE GMBH | MPZ2012S601AT | EVT | 1 |  |  | 10 | G | L2,L3,L4,L5,L6,L7,L8,L9,L10,L11 |  |  |  |  |  |  |
|  |  |  |  |  | 31 | 720103500-059-G |  | FB,600 Ohm@100MHz,+/-25%,2A,100mOhm,G,SMD0805 | TAI-TECH Advanced Electronics Co., Ltd. | HCB2012KF-601T20 |  |  | 2 |  |  | G |  |  |  |  |  |  |  |
|  |  |  |  |  | 31 | 720103500-174-G |  | FB,600 Ohm@100MHz,+/-25%,2A,100mOhm,G,SMD0805 | MAX ECHO TECHNOLOGIES CORP | ACMS201209A601 2A |  |  |  | 3 |  | G |  |  |  |  |  |  |  |
| Multi | ND | ND | N | 32 | 32 | 720105N00-016-G | - | FB,30 Ohm@100MHz,+/-33%,5A,10mOhm,G,SMD0805 | TDK ELECTRONICS EUROPE GMBH | MPZ2012S300AT |  |  | 2 |  | 12 | G | L12,L13,L14,L15,L16,L17,L18,L19,L20,L21,L22,L23 |  |  |  |  |  |  |
|  |  |  |  |  | 32 | 72010A700-029-G |  | FB,30 Ohm@100MHz,+/-25%,6A,15mOhm,G,SMD0805 | VISHAY ENTER TECHNO LOGY.INC | ILHB0805ER300V |  |  |  | 3 |  | G |  |  |  |  |  |  |  |
|  |  |  |  |  | 32 | 720103401-059-G |  | FB,Multilayer,20mOhm,30Ohm@100MHz,+/-25%,5A,,SMD0805,G | TAI-TECH ADVANCED ELECTRONICS CO., LTD. | HCB2012VF-300T50 | EVT | 1 |  |  |  | G |  |  |  |  |  |  |  |
| Multi | Y | ND | Y(2) | 33 | 33 | 720101L00-015-G | R8955 | FB,600 Ohm@100MHz,+/-25%,200mA,500mOhm,G,SMD0603 | MURATA ELEC. NORTH AMERICA | BLM18AG601SN1D | EVT | 1 |  |  | 1 | G | L24 |  |  |  |  |  |  |
|  |  |  |  |  | 33 | 720101L00-074-G |  | FB,600Ohm@100MHz,+/-25%,200mA,500mOhm,SMD0603,G | CHILISIN ELECTRONICS CORP. | SBK160808T-601Y-N |  |  |  | 3 |  | G |  |  |  |  |  |  |  |
|  |  |  |  |  | 33 | 720105E04-016-G |  | FB,600Ohm@100MHz,+/-25%,500mA,400mOhm,SMD0603,G | TDK ELECTRONICS EUROPE GMBH | MMZ1608B601CTAH0 |  |  | 2 |  |  | G |  |  |  |  |  |  |  |
| Multi | ND | ND | N | 34 | 34 | 62120BA00-022-G |  | SPEA,CAP,180uF,+/-20%,16V,105C,G,SMD6.3*5.9,ESR<=22mOhm | SANYO ELECTRIC CO., LTD. | 16SVPF180M | EVT | 1 |  | 3 | 1 | G | PECCE1 |  |  |  |  |  |  |
|  |  |  |  |  | 34 | 62120D701-021-G |  | SPEA CAP,180uF,+/-20%,16V,105C,G,SMD6.3*5.8,ESR<=22mOhm | NIPPON CHEMI-CON CORPORATION | APXG160ARA181MF61G |  |  | 2 |  |  | G |  |  |  |  |  |  |  |
| Single | N | ND | Y(3) | 35 | 35 | 62120ES00-024-G | - | SPEA CAP,560uF,+/-20%,2V,105C,G,SMD2816,ESR<=3mOhm | PANASONIC INDUSTRIAL CO.,LTD. | EEFGX0D561L | EVT | 1 | 2 | 3 | 4 | G | PECCE3,PECCE4,PECCE5,PECCE6 |  |  |  |  |  |  |
| Multi | Y | 2 | Y(3) | 36 | 36 | 620103K00-015-G | - | CAP,1nF,+/-10%,X7R,50V,G,SMD0402 | MURATA ELEC. NORTH AMERICA | GRM155R71H102K | EVT | 1 | 2 | 3 | 3 | G | PECC1,PELC17,PFCC19 |  |  |  |  |  |  |
|  |  |  |  |  | 36 | 620103K00-012-G |  | CAP,1nF,+/-10%,X7R,50V,G,SMD0402 | WALSIN TECHNOLOGY CORPORATION | 0402B102K500CT |  | 1 | 2 | 3 |  | G |  |  |  |  |  |  |  |
|  |  |  |  |  | 36 | 620103K00-026-G |  | CAP,1nF,+/-10%,X7R,50V,G,SMD0402 | SAMSUNG SEMICONDUCTOR | CL05B102KB5NNNC |  | 1 | 2 | 3 |  | G |  |  |  |  |  |  |  |
|  |  |  |  |  | 36 | 620103K00-023-G |  | CAP,1nF,+/-10%,X7R,50V,G,SMD0402 | TAIYO ELECTRIC IND.CO.LTD | UMK105B7102KV-F |  | 1 | 2 | 3 |  | G |  |  |  |  |  |  |  |
| Multi | ND | ND | Y(3) | 37 | 37 | 62010FY00-015-G | - | CAP,1.5nF,+/-10%,X7R,50V,G,SMD0402 | MURATA ELEC. NORTH AMERICA | GRM155R71H152K | EVT | 1 | 2 | 3 | 1 | G | PECC2 |  |  |  |  |  |  |
|  |  |  |  |  | 37 | 62010FY00-012-G |  | CAP,1.5nF,+/-10%,X7R,50V,G,SMD0402 | WALSIN TECHNOLOGY CORPORATION | 0402B152K500CT |  | 1 | 2 | 3 |  | G |  |  |  |  |  |  |  |
|  |  |  |  |  | 37 | 62010FY00-026-G |  | CAP,1.5nF,+/-10%,X7R,50V,G,SMD0402 | SAMSUNG SEMICONDUCTOR | CL05B152KB5NNNC |  | 1 | 2 | 3 |  | G |  |  |  |  |  |  |  |
|  |  |  |  |  | 37 | 62010FY00-023-G |  | CAP,1.5nF,+/-10%,X7R,50V,G,SMD0402 | TAIYO ELECTRIC IND.CO.LTD | UMK105B7152KV-F |  | 1 | 2 | 3 |  | G |  |  |  |  |  |  |  |
| Multi | Y | 2 | Y(3) | 38 | 38 | 620103U00-015-G | - | CAP,470pF,+/-10%,X7R,50V,G,SMD0402 | MURATA ELEC. NORTH AMERICA | GRM155R71H471K |  | 1 | 2 | 3 | 1 | G | PECC4 |  |  |  |  |  |  |
|  |  |  |  |  | 38 | 620103U00-012-G |  | CAP,470pF,+/-10%,X7R,50V,G,SMD0402 | WALSIN TECHNOLOGY CORPORATION | 0402B471K500CT | EVT | 1 | 2 | 3 |  | G |  |  |  |  |  |  |  |
|  |  |  |  |  | 38 | 620103U00-026-G |  | CAP,470pF,+/-10%,X7R,50V,G,SMD0402 | SAMSUNG SEMICONDUCTOR | CL05B471KB5NNNC |  | 1 | 2 | 3 |  | G |  |  |  |  |  |  |  |
|  |  |  |  |  | 38 | 620103U00-023-G |  | CAP,470pF,+/-10%,X7R,50V,G,SMD0402 | TAIYO ELECTRIC IND.CO.LTD | UMK105B7471KV-F |  | 1 | 2 | 3 |  | G |  |  |  |  |  |  |  |
| Multi | ND | ND | Y(3) | 39 | 39 | 620114T00-015-G | - | CAP,330nF,+/-10%,X5R,10V,G,SMD0402 | MURATA ELEC. NORTH AMERICA | GRM155R61A334K | EVT | 1 | 2 | 3 | 1 | G | PECC7 |  |  |  |  |  |  |
|  |  |  |  |  | 39 | 620114T00-012-G |  | CAP,330nF,+/-10%,X5R,10V,G,SMD0402 | WALSIN TECHNOLOGY CORPORATION | 0402X334K100CT |  | 1 | 2 | 3 |  | G |  |  |  |  |  |  |  |
|  |  |  |  |  | 39 | 620114T00-011-G |  | CAP,330nF,+/-10%,X5R,10V,G,SMD0402 | YAGEO CORPORATION COMPONENT | CC0402KRX5R6BB334 |  | 1 | 2 | 3 |  | G |  |  |  |  |  |  |  |
| Multi | ND | ND | Y(3) | 40 | 40 | 62012GE00-015-G | - | CAP,4.7uF,+/-20%,X7S,10V,G,SMD0603 | MURATA ELEC. NORTH AMERICA | GRM188C71A475M | EVT | 1 | 2 | 3 | 1 | G | PECC9 |  |  |  |  |  |  |
|  |  |  |  |  | 40 | 62012T800-023-G |  | CAP,4.7uF,+/-10%,X7S,10V,G,SMD0603 | TAIYO ELECTRIC IND.CO.LTD | LDK107BC7475KA-T |  | 1 | 2 | 3 |  | G |  |  |  |  |  |  |  |
| Multi | ND | ND | Y(1) | 41 | 41 | 62011F100-015-G |  | CAP,1uF,+/-10%,X7R,25V,G,SMD0603 | MURATA ELEC. NORTH AMERICA | GRM188R71E105K |  | 1 | 2 | 3 | 2 | G | PFCC3,PECC10 |  |  |  |  |  |  |
|  |  |  |  |  | 41 | 62011F100-023-G |  | CAP,1uF,+/-10%,X7R,25V,G,SMD0603 | TAIYO ELECTRIC IND.CO.LTD | TMK107B7105KA-T | EVT | 1 | 2 | 3 |  | G |  |  |  |  |  |  |  |
|  |  |  |  |  | 41 | 62011F100-026-G |  | CAP,1uF,+/-10%,X7R,25V,G,SMD0603 | SAMSUNG SEMICONDUCTOR | CL10B105KA8NNNC |  | 1 | 2 | 3 |  | G |  |  |  |  |  |  |  |
| Multi | ND | ND | Y(1) | 42 | 42 | 62010L800-015-G | - | CAP,1nF,+/-5%,NPO(C0G),50V,G,SMD0402 | MURATA ELEC. NORTH AMERICA | GRM1555C1H102J | EVT | 1 | 2 | 3 | 3 | G | PSCC5,PECC11,PECC12 |  |  |  |  |  |  |
|  |  |  |  |  | 42 | 62010L800-012-G |  | CAP,1nF,+/-5%,NPO(C0G),50V,G,SMD0402 | WALSIN TECHNOLOGY CORPORATION | 0402N102J500CT |  | 1 | 2 | 3 |  | G |  |  |  |  |  |  |  |
|  |  |  |  |  | 42 | 62010L800-026-G |  | CAP,1nF,+/-5%,NPO(C0G),50V,G,SMD0402 | SAMSUNG SEMICONDUCTOR | CL05C102JB5NNNC |  | 1 | 2 | 3 |  | G |  |  |  |  |  |  |  |
| Multi | ND |  | Y(3) | 43 | 43 | 62012P100-015-G |  | CAP,2.2uF,+/-20%,X7S,10V,G,SMD0402 | MURATA ELEC. NORTH AMERICA | GRM155C71A225M | EVT | 1 | 2 | 3 | 5 | G | PSRC5,PSLC5,PSGC5,PECC14,PECC17 |  |  |  |  |  |  |
|  |  |  |  |  | 43 | 62012P100-012-G |  | CAP,2.2uF,+/-20%,X7S,10V,G,SMD0402 | WALSIN TECHNOLOGY CORPORATION | 0402A225M100CT |  | 1 | 2 | 3 |  | G |  |  |  |  |  |  |  |
| Multi | Y | 2 | Y(3) | 44 | 44 | 620109700-015-G |  | CAP,3.3nF,+/-10%,X7R,50V,G,SMD0402 | MURATA ELEC. NORTH AMERICA | GRM155R71H332K | EVT | 1 | 2 | 3 | 7 | G | PLTC6,PECC20,PECC21,PECC22,PECC31,PECC32,PECC33 |  |  |  |  |  |  |
|  |  |  |  |  | 44 | 620109700-012-G |  | CAP,3.3nF,+/-10%,X7R,50V,G,SMD0402 | WALSIN TECHNOLOGY CORPORATION | 0402B332K500CT |  | 1 | 2 | 3 |  | G |  |  |  |  |  |  |  |
|  |  |  |  |  | 44 | 620109700-026-G |  | CAP,3.3nF,+/-10%,X7R,50V,G,SMD0402 | SAMSUNG SEMICONDUCTOR | CL05B332KB5NNNC |  | 1 | 2 | 3 |  | G |  |  |  |  |  |  |  |
| Multi | ND | ND | Y(1) | 45 | 45 | 62011HS01-015-G |  | CAP,10uF,+/-10%,X7R,25V,G,SMD1206 | MURATA ELEC. NORTH AMERICA | GRM31CR71E106K | EVT | 1 | 2 | 3 | 21 | G | PFCC5,PELC5,PFCC6,PELC6,PFCC7,PELC7,PFCC8,PELC8,PFCC9,PECC23,PECC24,PECC25,PECC26,PECC27,PECC28,PECC34,PECC35,PECC36,PECC37,PECC38,PECC39 |  |  |  |  |  |  |
|  |  |  |  |  | 45 | 62011HS00-026-G |  | CAP,10uF,+/-10%,X7R,25V,G,SMD1206 | SAMSUNG SEMICONDUCTOR | CL31B106KAHNNNE |  | 1 | 2 | 3 |  | G |  |  |  |  |  |  |  |
|  |  |  |  |  | 45 | 62011HS00-023-G |  | CAP,10uF,+/-10%,X7R,25V,G,SMD1206 | TAIYO ELECTRIC IND.CO.LTD | TMK316B7106KL-TD |  | 1 | 2 | 3 |  | G |  |  |  |  |  |  |  |
| Multi | Y | 2 | Y(1) | 46 | 46 | 620113A01-015-G | - | CAP,680pF,+/-5%,NPO,50V,G,SMD0402 | MURATA ELEC. NORTH AMERICA | GRM1555C1H681J | EVT | 1 | 2 | 3 | 2 | G | PECC42,PECC43 |  |  |  |  |  |  |
|  |  |  |  |  | 46 | 620113A00-012-G |  | CAP,680pF,+/-5%,NPO(C0G),50V,G,SMD0402 | WALSIN TECHNOLOGY CORPORATION | 0402N681J500LT |  | 1 | 2 | 3 |  | G |  |  |  |  |  |  |  |
|  |  |  |  |  | 46 | 620113A00-025-G |  | CAP,680pF,+/-5%,NPO(C0G),50V,G,SMD0402 | KEMET ELECTRONICS CORPORATION | C0402C681J5GAC |  | 1 | 2 | 3 |  | G |  |  |  |  |  |  |  |
|  |  |  |  |  | 46 | 620113A00-016-G |  | CAP,680pF,+/-5%,NPO(C0G),50V,G,SMD0402 | TDK ELECTRONICS EUROPE GMBH | C1005C0G1H681JT |  | 1 | 2 | 3 |  | G |  |  |  |  |  |  |  |
| Multi | N | ND | Y(3) | 47 | 47 | 62012G200-015-G | - | CAP,22uF,+/-20%,X6S,4V,G,SMD0603 | MURATA ELEC. NORTH AMERICA | GRM188C80G226M | EVT | 1 | 2 | 3 | 12 | G | PECC44,PECC45,PECC46,PECC47,PECC48,PECC49,PECC50,PECC51,PECC52,PECC53,PECC54,PECC55 |  |  |  |  |  |  |
|  |  |  |  |  | 47 | 62012G200-012-G |  | CAP,22uF,+/-20%,X6S,4V,G,SMD0603 | WALSIN TECHNOLOGY CORPORATION | 0603S226M4R0CT |  | 1 | 2 | 3 |  | G |  |  |  |  |  |  |  |
|  |  |  |  |  | 47 | 62012G200-026-G |  | CAP,22uF,+/-20%,X6S,4V,G,SMD0603 | SAMSUNG SEMICONDUCTOR | CL10X226MR8NUNE |  | 1 | 2 | 3 |  | G |  |  |  |  |  |  |  |
|  |  |  |  |  | 47 | 62012G200-023-G |  | CAP,22uF,+/-20%,X6S,4V,G,SMD0603 | TAIYO ELECTRIC IND.CO.LTD | AMK107BC6226MA-T |  | 1 | 2 | 3 |  | G |  |  |  |  |  |  |  |
| Single | ND | ND | N | 48 | 48 | 630330400-088-G | - | IND,150nH@100KHz,+/-10%,51A,304.5uOhm,SHLD,G,SMD | COOPER BUSSMANN, INC. | FP0906R1-R15-R | EVT | 1 | 2 | 3 | 2 | G | PECL1,PECL2 |  |  |  |  |  |  |
| Multi | ND | ND | N | 49 | 49 | 63033PG00-15A-G | - | IND,22nH@100KHz,+/-15%,22A,249.55uOhm,SHLD,G,SMD | The Inter-Technical Group, Inc. | SLC1615A-R022LHF | EVT | 1 |  |  | 1 | G | PECL3 |  |  |  |  |  |  |
|  |  |  |  |  | 49 | 63035Y500-129-G |  | IND,22nH@100KHz,+/-15%,22A,249.55uOhm,SHLD,G,SMD | MAG.LAYERS, SCIENTIFIC-TECHNICS (KUNSHAN) CO., LTD. | MSI-400404-22NL-I |  |  | 2 |  |  | G |  |  |  |  |  |  |  |
|  |  |  |  |  | 49 | 63035SH00-065-G |  | IND,22nH@100KHz,+/-15%,22A,249.55uOhm,SHLD,G,SMD | DELTA ELECTRONICS INDUSTRIAL CO.,LTD | HCB0439-220 |  |  |  | 3 |  | G |  |  |  |  |  |  |  |
| Multi | N |  | Y(5) | 50 | 50 | 61100LQ00-017-G |  | RES,20KOhm,+/-1%,1/16W,G,SMD0402 | KOA SPEER ELECTRONICS, INC. | RN731ETTP2002F50 |  | 1 | 2 | 3 | 1 | G | PECR1 |  |  |  |  |  |  |
|  |  |  |  |  | 50 | 61100LQ00-011-G |  | RES,20KOhm,+/-1%,1/16W,G,SMD0402 | YAGEO CORPORATION COMPONENT | RT0402FRE0720KL | EVT | 1 | 2 | 3 |  | G |  |  |  |  |  |  |  |
|  |  |  |  |  | 50 | 61100LQ00-044-G |  | RES,20KOhm,+/-1%,1/16W,G,SMD0402 | TA-I TECHNOLOGY CO., LTD. | RB04FTS2002 |  | 1 | 2 | 3 |  | G |  |  |  |  |  |  |  |
|  |  |  |  |  | 50 | 61100LQ00-012-G |  | RES,20KOhm,+/-1%,1/16W,G,SMD0402 | WALSIN TECHNOLOGY CORPORATION | WF04T2002FTL |  | 1 | 2 | 3 |  | G |  |  |  |  |  |  |  |
| Multi | N | ND | Y(4) | 51 | 51 | 61011FP00-017-G |  | RES,113KOhm,+/-1%,1/16W,G,SMD0402 | KOA SPEER ELECTRONICS, INC. | RK73H1ETTP1133F | EVT | 1 | 2 | 3 | 2 | G | PECR2,PECR13 |  |  |  |  |  |  |
|  |  |  |  |  | 51 | 61011FP00-011-G |  | RES,113KOhm,+/-1%,1/16W,G,SMD0402 | YAGEO CORPORATION COMPONENT | RC0402FR-07113KL |  | 1 | 2 | 3 |  | G |  |  |  |  |  |  |  |
|  |  |  |  |  | 51 | 61011FP00-012-G |  | RES,113KOhm,+/-1%,1/16W,G,SMD0402 | WALSIN TECHNOLOGY CORPORATION | WR04X1133FTL |  | 1 | 2 | 3 |  | G |  |  |  |  |  |  |  |
|  |  |  |  |  | 51 | 61011FP00-044-G |  | RES,113KOhm,+/-1%,1/16W,G,SMD0402 | TA-I TECHNOLOGY CO., LTD. | RM04FTN1133 |  | 1 | 2 | 3 |  | G |  |  |  |  |  |  |  |
| Multi | N | Other | Y(4) | 52 | 52 | 61011HP00-017-G |  | RES,44.2KOhm,+/-1%,1/16W,G,SMD0402 | KOA SPEER ELECTRONICS, INC. | RK73H1ETTP4422F | EVT | 1 | 2 | 3 | 1 | G | PECR3 |  |  |  |  |  |  |
|  |  |  |  |  | 52 | 61011HP00-012-G |  | RES,44.2KOhm,+/-1%,1/16W,G,SMD0402 | WALSIN TECHNOLOGY CORPORATION | WR04X4422FTL |  | 1 | 2 | 3 |  | G |  |  |  |  |  |  |  |
|  |  |  |  |  | 52 | 61011HP00-011-G |  | RES,44.2KOhm,+/-1%,1/16W,G,SMD0402 | YAGEO CORPORATION COMPONENT | RC0402FR-0744K2L |  | 1 | 2 | 3 |  | G |  |  |  |  |  |  |  |
|  |  |  |  |  | 52 | 61011HP00-044-G |  | RES,44.2KOhm,+/-1%,1/16W,G,SMD0402 | TA-I TECHNOLOGY CO., LTD. | RM04FTN4422 |  | 1 | 2 | 3 |  | G |  |  |  |  |  |  |  |
| Multi | ND | ND | Y(4) | 53 | 53 | 61011LH00-017-G |  | RES,9.31KOhm,+/-1%,1/16W,G,SMD0402 | KOA SPEER ELECTRONICS, INC. | RK73H1ETTP9311F | EVT | 1 | 2 | 3 | 1 | G | PECR4 |  |  |  |  |  |  |
|  |  |  |  |  | 53 | 61011LH00-011-G |  | RES,9.31KOhm,+/-1%,1/16W,G,SMD0402 | YAGEO CORPORATION COMPONENT | RC0402FR-079K31L |  | 1 | 2 | 3 |  | G |  |  |  |  |  |  |  |
|  |  |  |  |  | 53 | 61011LH00-012-G |  | RES,9.31KOhm,+/-1%,1/16W,G,SMD0402 | WALSIN TECHNOLOGY CORPORATION | WR04X9311FTL |  | 1 | 2 | 3 |  | G |  |  |  |  |  |  |  |
|  |  |  |  |  | 53 | 61011LH00-044-G |  | RES,9.31KOhm,+/-1%,1/16W,G,SMD0402 | TA-I TECHNOLOGY CO., LTD. | RM04FTN9311 |  | 1 | 2 | 3 |  | G |  |  |  |  |  |  |  |
| Multi | N | ND | Y(4) | 54 | 54 | 61011H600-017-G |  | RES,16.5KOhm,+/-1%,1/16W,G,SMD0402 | KOA SPEER ELECTRONICS, INC. | RK73H1ETTP1652F | EVT | 1 | 2 | 3 | 1 | G | PECR5 |  |  |  |  |  |  |
|  |  |  |  |  | 54 | 61011H600-011-G |  | RES,16.5KOhm,+/-1%,1/16W,G,SMD0402 | YAGEO CORPORATION COMPONENT | RC0402FR-0716K5L |  | 1 | 2 | 3 |  | G |  |  |  |  |  |  |  |
|  |  |  |  |  | 54 | 61011H600-012-G |  | RES,16.5KOhm,+/-1%,1/16W,G,SMD0402 | WALSIN TECHNOLOGY CORPORATION | WR04X1652FTL |  | 1 | 2 | 3 |  | G |  |  |  |  |  |  |  |
| Multi | ND |  | Y(4) | 55 | 55 | 610127Q00-017-G |  | RES,357KOhm,+/-1%,1/16W,G,SMD0402 | KOA SPEER ELECTRONICS, INC. | RK73H1ETTP3573F | EVT | 1 | 2 | 3 | 1 | G | PECR6 |  |  |  |  |  |  |
|  |  |  |  |  | 55 | 610127Q00-012-G |  | RES,357KOhm,+/-1%,1/16W,G,SMD0402 | WALSIN TECHNOLOGY CORPORATION | WR04X3573FTL |  | 1 | 2 | 3 |  | G |  |  |  |  |  |  |  |
|  |  |  |  |  | 55 | 610127Q00-011-G |  | RES,357KOhm,+/-1%,1/16W,G,SMD0402 | YAGEO CORPORATION COMPONENT | RC0402FR-07357KL |  | 1 | 2 | 3 |  | G |  |  |  |  |  |  |  |
|  |  |  |  |  | 55 | 610127Q00-044-G |  | RES,357KOhm,+/-1%,1/16W,G,SMD0402 | TA-I TECHNOLOGY CO., LTD. | RM04FTN3573 |  | 1 | 2 | 3 |  | G |  |  |  |  |  |  |  |
| Multi | ND | ND | Y(4) | 56 | 56 | 61011MG00-017-G |  | RES,42.2KOhm,+/-1%,1/16W,G,SMD0402 | KOA SPEER ELECTRONICS, INC. | RK73H1ETTP4222F |  | 1 | 2 | 3 | 1 | G | PECR7 |  |  |  |  |  |  |
|  |  |  |  |  | 56 | 61011MG00-012-G |  | RES,42.2KOhm,+/-1%,1/16W,G,SMD0402 | WALSIN TECHNOLOGY CORPORATION | WR04X4222FTL |  | 1 | 2 | 3 |  | G |  |  |  |  |  |  |  |
|  |  |  |  |  | 56 | 61011MG00-011-G |  | RES,42.2KOhm,+/-1%,1/16W,G,SMD0402 | YAGEO CORPORATION COMPONENT | RC0402FR-0742K2L | EVT | 1 | 2 | 3 |  | G |  |  |  |  |  |  |  |
|  |  |  |  |  | 56 | 61011MG00-044-G |  | RES,42.2KOhm,+/-1%,1/16W,G,SMD0402 | TA-I TECHNOLOGY CO., LTD. | RM04FTN4222 |  | 1 | 2 | 3 |  | G |  |  |  |  |  |  |  |
| Multi | ND | ND | Y(4) | 57 | 57 | 61011AQ00-017-G |  | RES,30.1KOhm,+/-1%,1/16W,G,SMD0402 | KOA SPEER ELECTRONICS, INC. | RK73H1ETTP3012F | EVT | 1 | 2 | 3 | 2 | G | PECR8,PECR12 |  |  |  |  |  |  |
|  |  |  |  |  | 57 | 61011AQ00-012-G |  | RES,30.1KOhm,+/-1%,1/16W,G,SMD0402 | WALSIN TECHNOLOGY CORPORATION | WR04X3012FTL |  | 1 | 2 | 3 |  | G |  |  |  |  |  |  |  |
|  |  |  |  |  | 57 | 61011AQ00-011-G |  | RES,30.1KOhm,+/-1%,1/16W,G,SMD0402 | YAGEO CORPORATION COMPONENT | RC0402FR-0730K1L |  | 1 | 2 | 3 |  | G |  |  |  |  |  |  |  |
|  |  |  |  |  | 57 | 61011AQ00-044-G |  | RES,30.1KOhm,+/-1%,1/16W,G,SMD0402 | TA-I TECHNOLOGY CO., LTD. | RM04FTN3012 |  | 1 | 2 | 3 |  | G |  |  |  |  |  |  |  |
| Multi | ND | ND | Y(5) | 58 | 58 | 61100K600-017-G |  | RES,24KOhm,+/-0.1%,1/16W,G,SMD0402 | KOA SPEER ELECTRONICS, INC. | RN731ETTP2402B25 |  | 1 |  |  | 1 | G | PECR9 |  |  |  |  |  |  |
|  |  |  |  |  | 58 | 61100K600-011-G |  | RES,24KOhm,+/-0.1%,1/16W,G,SMD0402 | YAGEO CORPORATION COMPONENT | RT0402BRD0724KL |  |  | 2 |  |  | G |  |  |  |  |  |  |  |
|  |  |  |  |  | 58 | 61100K600-044-G |  | RES,24KOhm,+/-0.1%,1/16W,G,SMD0402 | TA-I TECHNOLOGY CO., LTD. | RB04BTP2402 |  |  |  | 3 |  | G |  |  |  |  |  |  |  |
|  |  |  |  |  | 58 | 61100K600-012-G |  | RES,24KOhm,+/-0.1%,1/16W,G,SMD0402 | WALSIN TECHNOLOGY CORPORATION | WF04U2402BTL | EVT |  |  |  |  | G |  |  |  |  |  |  |  |
| Multi | ND | ND | Y(4) | 59 | 59 | 610116G00-017-G | - | RES,150KOhm,+/-1%,1/16W,G,SMD0402 | KOA SPEER ELECTRONICS, INC. | RK73H1ETTP1503F |  | 1 | 2 | 3 | 1 | G | PECR10 |  |  |  |  |  |  |
|  |  |  |  |  | 59 | 610116G00-011-G |  | RES,150KOhm,+/-1%,1/16W,G,SMD0402 | YAGEO CORPORATION COMPONENT | RC0402FR-07150KL | EVT | 1 | 2 | 3 |  | G |  |  |  |  |  |  |  |
|  |  |  |  |  | 59 | 610116G00-012-G |  | RES,150KOhm,+/-1%,1/16W,G,SMD0402 | WALSIN TECHNOLOGY CORPORATION | WR04X1503FTL |  | 1 | 2 | 3 |  | G |  |  |  |  |  |  |  |
|  |  |  |  |  | 59 | 610116G00-044-G |  | RES,150KOhm,+/-1%,1/16W,G,SMD0402 | TA-I TECHNOLOGY CO., LTD. | RM04FTN1503 |  | 1 | 2 | 3 |  | G |  |  |  |  |  |  |  |
| Multi | N | ND | Y(4) | 60 | 60 | 610114H00-017-G | - | RES,20KOhm,+/-1%,1/16W,G,SMD0402 | KOA SPEER ELECTRONICS, INC. | RK73H1ETTP2002F | EVT | 1 | 2 | 3 | 2 | G | PELR10,PECR11 |  |  |  |  |  |  |
|  |  |  |  |  | 60 | 610114H00-011-G |  | RES,20KOhm,+/-1%,1/16W,G,SMD0402 | YAGEO CORPORATION COMPONENT | RC0402FR-0720KL |  | 1 | 2 | 3 |  | G |  |  |  |  |  |  |  |
|  |  |  |  |  | 60 | 610114H00-012-G |  | RES,20KOhm,+/-1%,1/16W,G,SMD0402 | WALSIN TECHNOLOGY CORPORATION | WR04X2002FTL |  | 1 | 2 | 3 |  | G |  |  |  |  |  |  |  |
|  |  |  |  |  | 60 | 610114H00-044-G |  | RES,20KOhm,+/-1%,1/16W,G,SMD0402 | TA-I TECHNOLOGY CO., LTD. | RM04FTN2002 |  | 1 | 2 | 3 |  | G |  |  |  |  |  |  |  |
|  |  |  |  |  | 60 | 610114H00-024-G |  | RES,20KOhm,+/-1%,1/16W,G,SMD0402 | PANASONIC INDUSTRIAL CO.,LTD. | ERJ2RKF2002x |  | 1 | 2 | 3 |  | G |  |  |  |  |  |  |  |
|  |  |  |  |  | 60 | 610114H00-030-G |  | RES,20KOhm,+/-1%,1/16W,G,SMD0402 | ROHM CORPORATION | MCR01MZPF2002 |  | 1 | 2 | 3 |  | G |  |  |  |  |  |  |  |
|  |  |  |  |  | 60 | 610114H04-029-G |  | RES,20KOhm,+/-1%,1/16W,G,SMD0402 | VISHAY ENTER TECHNO LOGY.INC | CRCW040220K0FKEDC |  | 1 | 2 | 3 |  | G |  |  |  |  |  |  |  |
| Multi | ND | ND | Y(4) | 61 | 61 | 61011TN00-017-G |  | RES,39KOhm,+/-1%,1/16W,G,SMD0402 | KOA SPEER ELECTRONICS, INC. | RK73H1ETTP3902F | EVT | 1 | 2 | 3 | 1 | G | PECR14 |  |  |  |  |  |  |
|  |  |  |  |  | 61 | 61011TN00-011-G |  | RES,39KOhm,+/-1%,1/16W,G,SMD0402 | YAGEO CORPORATION COMPONENT | RC0402FR-0739KL |  | 1 | 2 | 3 |  | G |  |  |  |  |  |  |  |
|  |  |  |  |  | 61 | 61011TN00-012-G |  | RES,39KOhm,+/-1%,1/16W,G,SMD0402 | WALSIN TECHNOLOGY CORPORATION | WR04X3902FTL |  | 1 | 2 | 3 |  | G |  |  |  |  |  |  |  |
|  |  |  |  |  | 61 | 61011TN00-044-G |  | RES,39KOhm,+/-1%,1/16W,G,SMD0402 | TA-I TECHNOLOGY CO., LTD. | RM04FTN3902 |  | 1 | 2 | 3 |  | G |  |  |  |  |  |  |  |
| Multi | N | ND | Y(4) | 62 | 62 | 61010L300-017-G | - | RES,1KOhm,+/-1%,1/16W,G,SMD0402 | KOA SPEER ELECTRONICS, INC. | RK73H1ETTP1001F |  | 1 | 2 | 3 | 24 | G | PECR16,PECR25,R206,R207,R216,R217,R226,R227,R378,R379,R380,R387,R388,R389,R390,R403,R433,R434,R435,R438,R1401,R1402,R1537,R1538 |  |  |  |  |  |  |
|  |  |  |  |  | 62 | 61010L300-012-G |  | RES,1KOhm,+/-1%,1/16W,G,SMD0402 | WALSIN TECHNOLOGY CORPORATION | WR04X1001FTL |  | 1 | 2 | 3 |  | G |  |  |  |  |  |  |  |
|  |  |  |  |  | 62 | 61010L300-011-G |  | RES,1KOhm,+/-1%,1/16W,G,SMD0402 | YAGEO CORPORATION COMPONENT | RC0402FR-071KL | EVT | 1 | 2 | 3 |  | G |  |  |  |  |  |  |  |
|  |  |  |  |  | 62 | 61010L300-044-G |  | RES,1KOhm,+/-1%,1/16W,G,SMD0402 | TA-I TECHNOLOGY CO., LTD. | RM04FTN1001 |  | 1 | 2 | 3 |  | G |  |  |  |  |  |  |  |
|  |  |  |  |  | 62 | 61010L300-024-G |  | RES,1KOhm,+/-1%,1/16W,G,SMD0402 | PANASONIC INDUSTRIAL CO.,LTD. | ERJ2RKF1001X |  | 1 | 2 | 3 |  | G |  |  |  |  |  |  |  |
|  |  |  |  |  | 62 | 61010L300-029-G |  | RES,1KOhm,+/-1%,1/16W,G,SMD0402 | VISHAY ENTER TECHNO LOGY.INC | CRCW04021K00FKED |  | 1 | 2 | 3 |  | G |  |  |  |  |  |  |  |
| Multi | N | ND | Y(4) | 63 | 63 | 610107A00-017-G | - | RES,0 Ohm,+/-5%,1/16W,G,SMD0402 | KOA SPEER ELECTRONICS, INC. | RK73Z1ETTP | EVT | 1 | 2 | 3 | 79 | G | PLTR1,PSLR2,PSGR2,PSCR2,PFCR2,PELR2,PFCR3,PSCR7,PELR7,PSRR8,PSCR8,PSRR9,PSLR9,PSGR9,PFCR9,PELR9,R11,PFCR11,PSLR13,PSCR14,PSRR15,PSLR15,PSGR15,PELR15,PELR16,PFCR17,PELR17,PSRR18,PSLR18,PSGR18,PFCR18,PSCR22,PECR22,PECR23,PECR28,PECR30,PECR37,PECR38,PECR41,PECR42,PECR44,PECR52,PECR53,R131,R132,R133,R135,R137,R189,R198,R204,R205,R212,R213,R214,R215,R220,R221,R222,R223,R237,R250,R1387,R1388,R1410,R1441,R1445,R1513,R1514,R1515,R1516,R1520,R1524,R1535,R1536,R1540,PSCR3001,PSCR3002,PSCR3003 |  |  |  |  |  |  |
|  |  |  |  |  | 63 | 610107A00-012-G |  | RES,0 Ohm,+/-5%,1/16W,G,SMD0402 | WALSIN TECHNOLOGY CORPORATION | WR04X000PTL |  | 1 | 2 | 3 |  | G |  |  |  |  |  |  |  |
|  |  |  |  |  | 63 | 610107A00-011-G |  | RES,0 Ohm,+/-5%,1/16W,G,SMD0402 | YAGEO CORPORATION COMPONENT | RC0402JR-070RL |  | 1 | 2 | 3 |  | G |  |  |  |  |  |  |  |
|  |  |  |  |  | 63 | 610107A00-044-G |  | RES,0 Ohm,+/-5%,1/16W,G,SMD0402 | TA-I TECHNOLOGY CO., LTD. | RM04JTN0 |  | 1 | 2 | 3 |  | G |  |  |  |  |  |  |  |
|  |  |  |  |  | 63 | 610107A00-024-G |  | RES,0 Ohm,+/-5%,1/16W,G,SMD0402 | PANASONIC INDUSTRIAL CO.,LTD. | ERJ2GE0R00X |  | 1 | 2 | 3 |  | G |  |  |  |  |  |  |  |
|  |  |  |  |  | 63 | 610107A00-029-G |  | RES,0 Ohm,+/-5%,1/16W,G,SMD0402 | VISHAY ENTER TECHNO LOGY.INC | CRCW04020000Z0ED |  | 1 | 2 | 3 |  | G |  |  |  |  |  |  |  |
| Multi | ND | ND | Y(4) | 64 | 64 | 61010LE00-017-G |  | RES,12KOhm,+/-1%,1/16W,G,SMD0402 | KOA SPEER ELECTRONICS, INC. | RK73H1ETTP1202F |  | 1 | 2 | 3 | 1 | G | PECR24 |  |  |  |  |  |  |
|  |  |  |  |  | 64 | 61010LE00-011-G |  | RES,12KOhm,+/-1%,1/16W,G,SMD0402 | YAGEO CORPORATION COMPONENT | RC0402FR-0712KL |  | 1 | 2 | 3 |  | G |  |  |  |  |  |  |  |
|  |  |  |  |  | 64 | 61010LE00-012-G |  | RES,12KOhm,+/-1%,1/16W,G,SMD0402 | WALSIN TECHNOLOGY CORPORATION | WR04X1202FTL | EVT | 1 | 2 | 3 |  | G |  |  |  |  |  |  |  |
|  |  |  |  |  | 64 | 61010LE00-044-G |  | RES,12KOhm,+/-1%,1/16W,G,SMD0402 | TA-I TECHNOLOGY CO., LTD. | RM04FTN1202 |  | 1 | 2 | 3 |  | G |  |  |  |  |  |  |  |
| Multi | ND | ND | Y(4) | 65 | 65 | 610114S00-017-G | - | RES,4.99KOhm,+/-1%,1/16W,G,SMD0402 | KOA SPEER ELECTRONICS, INC. | RK73H1ETTP4991F |  | 1 | 2 | 3 | 3 | G | PSRR3,PSCR9,PECR26 |  |  |  |  |  |  |
|  |  |  |  |  | 65 | 610114S00-012-G |  | RES,4.99KOhm,+/-1%,1/16W,G,SMD0402 | WALSIN TECHNOLOGY CORPORATION | WR04X4991FTL | EVT | 1 | 2 | 3 |  | G |  |  |  |  |  |  |  |
|  |  |  |  |  | 65 | 610114S00-011-G |  | RES,4.99KOhm,+/-1%,1/16W,G,SMD0402 | YAGEO CORPORATION COMPONENT | RC0402FR-074K99L | EVT | 1 | 2 | 3 |  | G |  |  |  |  |  |  |  |
|  |  |  |  |  | 65 | 610114S00-044-G |  | RES,4.99KOhm,+/-1%,1/16W,G,SMD0402 | TA-I TECHNOLOGY CO., LTD. | RM04FTN4991 |  | 1 | 2 | 3 |  | G |  |  |  |  |  |  |  |
|  |  |  |  |  | 65 | 610114S00-024-G |  | RES,4.99KOhm,+/-1%,1/16W,G,SMD0402 | PANASONIC INDUSTRIAL CO.,LTD. | ERJ2RKF4991X |  | 1 | 2 | 3 |  | G |  |  |  |  |  |  |  |
| Multi | ND | ND | Y(4) | 66 | 66 | 61011GY00-017-G | - | RES,2.43KOhm,+/-1%,1/16W,G,SMD0402 | KOA SPEER ELECTRONICS, INC. | RK73H1ETTP2431F | EVT | 1 | 2 | 3 | 1 | G | PECR27 |  |  |  |  |  |  |
|  |  |  |  |  | 66 | 61011GY00-012-G |  | RES,2.43KOhm,+/-1%,1/16W,G,SMD0402 | WALSIN TECHNOLOGY CORPORATION | WR04X2431FTL |  | 1 | 2 | 3 |  | G |  |  |  |  |  |  |  |
|  |  |  |  |  | 66 | 61011GY00-011-G |  | RES,2.43KOhm,+/-1%,1/16W,G,SMD0402 | YAGEO CORPORATION COMPONENT | RC0402FR-072K43L |  | 1 | 2 | 3 |  | G |  |  |  |  |  |  |  |
|  |  |  |  |  | 66 | 61011GY00-044-G |  | RES,2.43KOhm,+/-1%,1/16W,G,SMD0402 | TA-I TECHNOLOGY CO., LTD. | RM04FTN2431 |  | 1 | 2 | 3 |  | G |  |  |  |  |  |  |  |
| Multi | ND |  | Y(4) | 67 | 67 | 61011C300-017-G |  | RES,2.2 Ohm,+/-1%,1/16W,G,SMD0402 | KOA SPEER ELECTRONICS, INC. | RK73H1ETTP2R20F |  | 1 | 2 | 3 | 1 | G | PECR29 |  |  |  |  |  |  |
|  |  |  |  |  | 67 | 61011C300-012-G |  | RES,2.2 Ohm,+/-1%,1/16W,G,SMD0402 | WALSIN TECHNOLOGY CORPORATION | WR04W2R20FTL |  | 1 | 2 | 3 |  | G |  |  |  |  |  |  |  |
|  |  |  |  |  | 67 | 61011C300-011-G |  | RES,2.2 Ohm,+/-1%,1/16W,G,SMD0402 | YAGEO CORPORATION COMPONENT | RC0402FR-072R2L | EVT | 1 | 2 | 3 |  | G |  |  |  |  |  |  |  |
|  |  |  |  |  | 67 | 61011C300-044-G |  | RES,2.2 Ohm,+/-1%,1/16W,G,SMD0402 | TA-I TECHNOLOGY CO., LTD. | RM04FTN2R20 |  | 1 | 2 | 3 |  | G |  |  |  |  |  |  |  |
| Multi | N | ND | Y(4) | 68 | 68 | 610108300-017-G | - | RES,0 Ohm,+/-5%,1/10W,G,SMD0603 | KOA SPEER ELECTRONICS, INC. | RK73Z1JTTD | EVT | 1 | 2 | 3 | 2 | G | PECR31,PECR32 |  |  |  |  |  |  |
|  |  |  |  |  | 68 | 610108300-012-G |  | RES,0 Ohm,+/-5%,1/10W,G,SMD0603 | WALSIN TECHNOLOGY CORPORATION | WR06X000PTL |  | 1 | 2 | 3 |  | G |  |  |  |  |  |  |  |
|  |  |  |  |  | 68 | 610108300-011-G |  | RES,0 Ohm,+/-5%,1/10W,G,SMD0603 | YAGEO CORPORATION COMPONENT | RC0603JR-070RL |  | 1 | 2 | 3 |  | G |  |  |  |  |  |  |  |
|  |  |  |  |  | 68 | 610108300-044-G |  | RES,0 Ohm,+/-5%,1/10W,G,SMD0603 | TA-I TECHNOLOGY CO., LTD. | RM06JTN0 |  | 1 | 2 | 3 |  | G |  |  |  |  |  |  |  |
|  |  |  |  |  | 68 | 610108300-024-G |  | RES,0 Ohm,+/-5%,1/10W,G,SMD0603 | PANASONIC INDUSTRIAL CO.,LTD. | ERJ3GEY0R00V |  | 1 | 2 | 3 |  | G |  |  |  |  |  |  |  |
| Multi | N | ND | Y(4) | 69 | 69 | 610113800-017-G | - | RES,10 Ohm,+/-1%,1/16W,G,SMD0402 | KOA SPEER ELECTRONICS, INC. | RK73H1ETTP10R0F |  | 1 | 2 | 3 | 13 | G | PFCR4,PECR33,PECR34,R105,R106,R107,R108,R109,R110,R111,R112,R113,R114 |  |  |  |  |  |  |
|  |  |  |  |  | 69 | 610113800-012-G |  | RES,10 Ohm,+/-1%,1/16W,G,SMD0402 | WALSIN TECHNOLOGY CORPORATION | WR04X10R0FTL |  | 1 | 2 | 3 |  | G |  |  |  |  |  |  |  |
|  |  |  |  |  | 69 | 610113800-011-G |  | RES,10 Ohm,+/-1%,1/16W,G,SMD0402 | YAGEO CORPORATION COMPONENT | RC0402FR-0710RL | EVT | 1 | 2 | 3 |  | G |  |  |  |  |  |  |  |
|  |  |  |  |  | 69 | 610113800-044-G |  | RES,10 Ohm,+/-1%,1/16W,G,SMD0402 | TA-I TECHNOLOGY CO., LTD. | RM04FTN10R0 |  | 1 | 2 | 3 |  | G |  |  |  |  |  |  |  |
| Multi | ND | ND | Y(4) | 70 | 70 | 61011HA00-017-G |  | RES,1 Ohm,+/-1%,1/16W,G,SMD0402 | KOA SPEER ELECTRONICS, INC. | RK73H1ETTP1R00F |  | 1 | 2 | 3 | 7 | G | PSCR4,PSRR5,PSLR5,PSGR5,PFCR7,PECR39,PECR40 |  |  |  |  |  |  |
|  |  |  |  |  | 70 | 61011HA00-012-G |  | RES,1 Ohm,+/-1%,1/16W,G,SMD0402 | WALSIN TECHNOLOGY CORPORATION | WR04W1R00FTL | EVT | 1 | 2 | 3 |  | G |  |  |  |  |  |  |  |
|  |  |  |  |  | 70 | 61011HA00-011-G |  | RES,1 Ohm,+/-1%,1/16W,G,SMD0402 | YAGEO CORPORATION COMPONENT | RC0402FR-071RL |  | 1 | 2 | 3 |  | G |  |  |  |  |  |  |  |
|  |  |  |  |  | 70 | 61011HA00-044-G |  | RES,1 Ohm,+/-1%,1/16W,G,SMD0402 | TA-I TECHNOLOGY CO., LTD. | RM04FTN1R00 | EVT | 1 | 2 | 3 |  | G |  |  |  |  |  |  |  |
|  |  |  |  |  | 70 | 61011HA00-029-G |  | RES,1 Ohm,+/-1%,1/16W,G,SMD0402 | VISHAY ENTER TECHNO LOGY.INC | CRCW04021R00FNED |  | 1 | 2 | 3 |  | G |  |  |  |  |  |  |  |
| Multi | N | ND | Y(4) | 71 | 71 | 61010FE00-017-G | - | RES,100 Ohm,+/-1%,1/16W,G,SMD0402 | KOA SPEER ELECTRONICS, INC. | RK73H1ETTP1000F |  | 1 | 2 | 3 | 30 | G | PECR43,R73,R74,R96,R1380,R1449,R1450,R1455,R1456,R1457,R1458,R1459,R1460,R1461,R1462,R1463,R1464,R1465,R1466,R1467,R1468,R1469,R1470,R1471,R1472,R1473,R1474,R1475,R1476,R1477 |  |  |  |  |  |  |
|  |  |  |  |  | 71 | 61010FE00-012-G |  | RES,100 Ohm,+/-1%,1/16W,G,SMD0402 | WALSIN TECHNOLOGY CORPORATION | WR04X1000FTL |  | 1 | 2 | 3 |  | G |  |  |  |  |  |  |  |
|  |  |  |  |  | 71 | 61010FE00-011-G |  | RES,100 Ohm,+/-1%,1/16W,G,SMD0402 | YAGEO CORPORATION COMPONENT | RC0402FR-07100RL | EVT | 1 | 2 | 3 |  | G |  |  |  |  |  |  |  |
|  |  |  |  |  | 71 | 61010FE00-044-G |  | RES,100 Ohm,+/-1%,1/16W,G,SMD0402 | TA-I TECHNOLOGY CO., LTD. | RM04FTN1000 |  | 1 | 2 | 3 |  | G |  |  |  |  |  |  |  |
| Multi | ND | ND | Y(4) | 72 | 72 | 610125N00-017-G |  | RES,3.3 Ohm,+/-1%,1/16W,G,SMD0402 | KOA SPEER ELECTRONICS, INC. | RK73H1ETTP3R30F | EVT | 1 | 2 | 3 | 2 | G | PECR45,PECR46 |  |  |  |  |  |  |
|  |  |  |  |  | 72 | 610125N00-012-G |  | RES,3.3 Ohm,+/-1%,1/16W,G,SMD0402 | WALSIN TECHNOLOGY CORPORATION | WR04W3R30FTL |  | 1 | 2 | 3 |  | G |  |  |  |  |  |  |  |
|  |  |  |  |  | 72 | 610125N00-011-G |  | RES,3.3 Ohm,+/-1%,1/16W,G,SMD0402 | YAGEO CORPORATION COMPONENT | RC0402FR-073R3L |  | 1 | 2 | 3 |  | G |  |  |  |  |  |  |  |
|  |  |  |  |  | 72 | 610125N00-044-G |  | RES,3.3 Ohm,+/-1%,1/16W,G,SMD0402 | TA-I TECHNOLOGY CO., LTD. | RM04FTN3R30 |  | 1 | 2 | 3 |  | G |  |  |  |  |  |  |  |
| Multi | N | Other | Y(4) | 73 | 73 | 610101100-017-G |  | RES,1 Ohm,+/-1%,1/10W,G,SMD0603 | KOA SPEER ELECTRONICS, INC. | RK73H1JTTD1R00F | EVT | 1 | 2 | 3 | 9 | G | PELR4,PELR11,PELR13,PFCR14,PFCR16,PECR47,PECR48,PECR49,PECR50 |  |  |  |  |  |  |
|  |  |  |  |  | 73 | 610101100-011-G |  | RES,1 Ohm,+/-1%,1/10W,G,SMD0603 | YAGEO CORPORATION COMPONENT | RC0603FR-071RL |  | 1 | 2 | 3 |  | G |  |  |  |  |  |  |  |
|  |  |  |  |  | 73 | 610101100-012-G |  | RES,1 Ohm,+/-1%,1/10W,G,SMD0603 | WALSIN TECHNOLOGY CORPORATION | WR06W1R00FTL |  | 1 | 2 | 3 |  | G |  |  |  |  |  |  |  |
|  |  |  |  |  | 73 | 610101100-044-G |  | RES,1 Ohm,+/-1%,1/10W,G,SMD0603 | TA-I TECHNOLOGY CO., LTD. | RM06FTN1R00 |  | 1 | 2 | 3 |  | G |  |  |  |  |  |  |  |
| Multi | N |  | N | 74 | 74 | 32022VJ00-183-G |  | IC,PWM Controller,TPS53641RSBR,G,QFN-40,SMD | TEXAS INSTRUMENTS | TPS53641RSBR | EVT | 1 |  | 3 | 1 | G | PECU1 |  |  |  |  |  |  |
|  |  |  |  |  | 74 | 32023H600-183-G |  | IC,PWM Controller,TPS53641RSBT,G,QFN-40,SMD | TEXAS INSTRUMENTS | TPS53641RSBT |  |  | 2 |  |  | G |  |  |  |  |  |  |  |
| Single | ND |  | N | 75 | 75 | 320240000-183-G |  | IC,PWM Controller,CSD95472Q5MC,G,SON-13,SMD | TEXAS INSTRUMENTS | CSD95472Q5MC | EVT | 1 | 2 | 3 | 2 | G | PECU2,PECU3 |  |  |  |  |  |  |
| Multi | N | ND | Y(1) | 76 | 76 | 62012PT00-015-G | - | CAP,22uF,+/-20%,X6S,16V,G,SMD0805 | MURATA ELEC. NORTH AMERICA | GRM21BC81C226M | EVT | 1 | 2 | 3 | 15 | G | PSRC7,PLTC7,PSRC8,PLTC8,PLTC9,PLTC10,PSRC11,PSRC12,PELC12,PELC13,PELC14,PSRC15,PELC15,PELC18,PELC19 |  |  |  |  |  |  |
|  |  |  |  |  | 76 | 62012PT00-023-G |  | CAP,22uF,+/-20%,X6S,16V,G,SMD0805 | TAIYO ELECTRIC IND.CO.LTD | EDK212BC6226MG-T |  | 1 | 2 | 3 |  | G |  |  |  |  |  |  |  |
| Multi | Y | 2 | Y(1) | 77 | 77 | 62011G000-015-G | - | CAP,1uF,+/-10%,X5R,16V,G,SMD0402 | MURATA ELEC. NORTH AMERICA | GRM155R61C105K | EVT | 1 | 2 | 3 | 1 | G | PELC16 |  |  |  |  |  |  |
|  |  |  |  |  | 77 | 62011G000-026-G |  | CAP,1uF,+/-10%,X5R,16V,G,SMD0402 | SAMSUNG SEMICONDUCTOR | CL05A105KO5NNNC |  | 1 | 2 | 3 |  | G |  |  |  |  |  |  |  |
|  |  |  |  |  | 77 | 62011G000-023-G |  | CAP,1uF,+/-10%,X5R,16V,G,SMD0402 | TAIYO ELECTRIC IND.CO.LTD | EMK105BJ105KV-F |  | 1 | 2 | 3 |  | G |  |  |  |  |  |  |  |
|  |  |  |  |  | 77 | 62011G000-012-G |  | CAP,1uF,+/-10%,X5R,16V,G,SMD0402 | WALSIN TECHNOLOGY CORPORATION | 0402X105K160CT |  | 1 | 2 | 3 |  | G |  |  |  |  |  |  |  |
| Multi | N |  | Y(2) | 78 | 78 | 72010RE00-015-G |  | FB,26 Ohm@100MHz,+/-25%,6A,7mOhm,G,SMD0603 | MURATA ELEC. NORTH AMERICA | BLM18KG260TN1D | EVT | 1 |  | 3 | 8 | G | PSRL1,PSLL1,PSGL1,PLTL1,PFCL1,PELL1,PELL3,PELL4 |  |  |  |  |  |  |
|  |  |  |  |  | 78 | 72010SJ00-059-G |  | FB,Multilayer,10mOhm,26Ohm@100MHz,+/-25%,6A,,SMD0603,G | TAI-TECH ADVANCED ELECTRONICS CO., LTD. | HCB1608KF-260T60 |  |  | 2 |  |  | G |  |  |  |  |  |  |  |
| Single | ND |  | N | 79 | 79 | 63033RJ00-15A-G |  | IND,4.7uH@100KHz,+/-20%,3.5A,65mOhm,SHLD,G,SMD | The Inter-Technical Group, Inc. | SMHC2011-4R7MHF | EVT | 1 | 2 | 3 | 1 | G | PELL2 |  |  |  |  |  |  |
| Multi | ND | ND | Y(5) | 80 | 80 | 611003200-017-G |  | RES,10KOhm,+/-0.1%,1/16W,G,SMD0402 | KOA SPEER ELECTRONICS, INC. | RN731ETTP1002B25 | EVT | 1 |  |  | 2 | G | PELR3,PFCR5 |  |  |  |  |  |  |
|  |  |  |  |  | 80 | 611003200-011-G |  | RES,10KOhm,+/-0.1%,1/16W,G,SMD0402 | YAGEO CORPORATION COMPONENT | RT0402BRE0710KL |  |  | 2 |  |  | G |  |  |  |  |  |  |  |
|  |  |  |  |  | 80 | 611003200-044-G |  | RES,10KOhm,+/-0.1%,1/16W,G,SMD0402 | TA-I TECHNOLOGY CO., LTD. | RB04BTP1002 |  |  |  | 3 |  | G |  |  |  |  |  |  |  |
|  |  |  |  |  | 80 | 611003200-012-G |  | RES,10KOhm,+/-0.1%,1/16W,G,SMD0402 | WALSIN TECHNOLOGY CORPORATION | WF04U1002BTL |  |  |  |  |  | G |  |  |  |  |  |  |  |
| Multi | ND |  | Y(5) | 81 | 81 | 61100UT00-017-G |  | RES,20.5KOhm,+/-0.1%,1/16W,G,SMD0402 | KOA SPEER ELECTRONICS, INC. | RN731ETTP2052B25 |  | 1 |  |  | 1 | G | PELR5 |  |  |  |  |  |  |
|  |  |  |  |  | 81 | 61100UT00-011-G |  | RES,20.5KOhm,+/-0.1%,1/16W,G,SMD0402 | YAGEO CORPORATION COMPONENT | RT0402BRD0720K5L |  |  | 2 |  |  | G |  |  |  |  |  |  |  |
|  |  |  |  |  | 81 | 61100UT00-044-G |  | RES,20.5KOhm,+/-0.1%,1/16W,G,SMD0402 | TA-I TECHNOLOGY CO., LTD. | RB04BTP2052 |  |  |  | 3 |  | G |  |  |  |  |  |  |  |
|  |  |  |  |  | 81 | 61100UT00-012-G |  | RES,20.5KOhm,+/-0.1%,1/16W,G,SMD0402 | WALSIN TECHNOLOGY CORPORATION | WF04U2052BTL | EVT |  |  |  |  | G |  |  |  |  |  |  |  |
| Multi | ND | ND | Y(4) | 82 | 82 | 61010LA00-017-G | - | RES,4.7KOhm,+/-1%,1/16W,G,SMD0402 | KOA SPEER ELECTRONICS, INC. | RK73H1ETTP4701F | EVT | 1 | 2 | 3 | 8 | G | PSCR1,PELR6,PFCR8,R229,R230,R251,R252,R1539 |  |  |  |  |  |  |
|  |  |  |  |  | 82 | 61010LA00-012-G |  | RES,4.7KOhm,+/-1%,1/16W,G,SMD0402 | WALSIN TECHNOLOGY CORPORATION | WR04X4701FTL |  | 1 | 2 | 3 |  | G |  |  |  |  |  |  |  |
|  |  |  |  |  | 82 | 61010LA00-011-G |  | RES,4.7KOhm,+/-1%,1/16W,G,SMD0402 | YAGEO CORPORATION COMPONENT | RC0402FR-074K7L |  | 1 | 2 | 3 |  | G |  |  |  |  |  |  |  |
|  |  |  |  |  | 82 | 61010LA00-044-G |  | RES,4.7KOhm,+/-1%,1/16W,G,SMD0402 | TA-I TECHNOLOGY CO., LTD. | RM04FTN4701 |  | 1 | 2 | 3 |  | G |  |  |  |  |  |  |  |
| Multi | ND | ND | Y(4) | 83 | 83 | 61011UM00-017-G | - | RES,240KOhm,+/-1%,1/16W,G,SMD0402 | KOA SPEER ELECTRONICS, INC. | RK73H1ETTP2403F | EVT | 1 | 2 | 3 | 2 | G | PELR12,PFCR13 |  |  |  |  |  |  |
|  |  |  |  |  | 83 | 61011UM00-011-G |  | RES,240KOhm,+/-1%,1/16W,G,SMD0402 | YAGEO CORPORATION COMPONENT | RC0402FR-07240KL |  | 1 | 2 | 3 |  | G |  |  |  |  |  |  |  |
|  |  |  |  |  | 83 | 61011UM00-012-G |  | RES,240KOhm,+/-1%,1/16W,G,SMD0402 | WALSIN TECHNOLOGY CORPORATION | WR04X2403FTL |  | 1 | 2 | 3 |  | G |  |  |  |  |  |  |  |
|  |  |  |  |  | 83 | 61011UM00-044-G |  | RES,240KOhm,+/-1%,1/16W,G,SMD0402 | TA-I TECHNOLOGY CO., LTD. | RM04FTN2403 |  | 1 | 2 | 3 |  | G |  |  |  |  |  |  |  |
| Multi | N | Other | Y(4) | 84 | 84 | 61011YJ00-017-G |  | RES,71.5KOhm,+/-1%,1/16W,G,SMD0402 | KOA SPEER ELECTRONICS, INC. | RK73H1ETTP7152F | EVT | 1 | 2 | 3 | 2 | G | PELR14,PFCR15 |  |  |  |  |  |  |
|  |  |  |  |  | 84 | 61011YJ00-011-G |  | RES,71.5KOhm,+/-1%,1/16W,G,SMD0402 | YAGEO CORPORATION COMPONENT | RC0402FR-0771K5L |  | 1 | 2 | 3 |  | G |  |  |  |  |  |  |  |
|  |  |  |  |  | 84 | 61011YJ00-012-G |  | RES,71.5KOhm,+/-1%,1/16W,G,SMD0402 | WALSIN TECHNOLOGY CORPORATION | WR04X7152FTL |  | 1 | 2 | 3 |  | G |  |  |  |  |  |  |  |
|  |  |  |  |  | 84 | 61011YJ00-044-G |  | RES,71.5KOhm,+/-1%,1/16W,G,SMD0402 | TA-I TECHNOLOGY CO., LTD. | RM04FTN7152 |  | 1 | 2 | 3 |  | G |  |  |  |  |  |  |  |
| Single | Y |  | Y(1) | 85 | 85 | 32013BY00-183-G |  | IC,Regulator,TPS53513RVER,8A,ADJ,G,QFN-28,SMD | TEXAS INSTRUMENTS | TPS53513RVER | EVT | 1 | 2 | 3 | 1 | G | PELU1 |  |  |  |  |  |  |
| Single | N |  | N | 86 | 86 | 63033JL00-15A-G |  | IND,470nH@100KHz,+/-20%,13.5A,4.2mOhm,SHLD,G,SMD | The Inter-Technical Group, Inc. | SMHC2511-R47MHF | EVT | 1 | 2 | 3 | 1 | G | PFCL2 |  |  |  |  |  |  |
| Multi | ND | ND | Y(4) | 87 | 87 | 610116N00-017-G |  | RES,5.1KOhm,+/-1%,1/16W,G,SMD0402 | KOA SPEER ELECTRONICS, INC. | RK73H1ETTP5101F | EVT | 1 | 2 | 3 | 1 | G | PFCR6 |  |  |  |  |  |  |
|  |  |  |  |  | 87 | 610116N00-011-G |  | RES,5.1KOhm,+/-1%,1/16W,G,SMD0402 | YAGEO CORPORATION COMPONENT | RC0402FR-075K1L |  | 1 | 2 | 3 |  | G |  |  |  |  |  |  |  |
|  |  |  |  |  | 87 | 610116N00-012-G |  | RES,5.1KOhm,+/-1%,1/16W,G,SMD0402 | WALSIN TECHNOLOGY CORPORATION | WR04X5101FTL |  | 1 | 2 | 3 |  | G |  |  |  |  |  |  |  |
|  |  |  |  |  | 87 | 610116N00-044-G |  | RES,5.1KOhm,+/-1%,1/16W,G,SMD0402 | TA-I TECHNOLOGY CO., LTD. | RM04FTN5101 |  | 1 | 2 | 3 |  | G |  |  |  |  |  |  |  |
| Multi | N | ND | Y(4) | 88 | 88 | 61011VM00-017-G | - | RES,57.6KOhm,+/-1%,1/16W,G,SMD0402 | KOA SPEER ELECTRONICS, INC. | RK73H1ETTP5762F |  | 1 | 2 | 3 | 1 | G | PFCR12 |  |  |  |  |  |  |
|  |  |  |  |  | 88 | 61011VM00-011-G |  | RES,57.6KOhm,+/-1%,1/16W,G,SMD0402 | YAGEO CORPORATION COMPONENT | RC0402FR-0757K6L | EVT | 1 | 2 | 3 |  | G |  |  |  |  |  |  |  |
|  |  |  |  |  | 88 | 61011VM00-012-G |  | RES,57.6KOhm,+/-1%,1/16W,G,SMD0402 | WALSIN TECHNOLOGY CORPORATION | WR04X5762FTL |  | 1 | 2 | 3 |  | G |  |  |  |  |  |  |  |
|  |  |  |  |  | 88 | 61011VM00-044-G |  | RES,57.6KOhm,+/-1%,1/16W,G,SMD0402 | TA-I TECHNOLOGY CO., LTD. | RM04FTN5762 |  | 1 | 2 | 3 |  | G |  |  |  |  |  |  |  |
| Single | Y | ND | Y(1) | 89 | 89 | 320143Y00-183-G | - | IC,Regulator,TPS548A20RVER,ADJ,15A,G,VQFN-28,SMD | TEXAS INSTRUMENTS | TPS548A20RVER | EVT | 1 | 2 | 3 | 1 | G | PFCU1 |  |  |  |  |  |  |
| Single | ND |  | Y(1) | 90 | 90 | 62012T500-015-G |  | CAP,22uF,+/-20%,X7S,25V,G,SMD1206 | MURATA ELEC. NORTH AMERICA | GRM31CC71E226ME11L | EVT | 1 | 2 | 3 | 18 | G | PSRC2,PSLC2,PSGC2,PLTC2,PLTC3,PSCC6,PSCC7,PSCC8,PSCC9,PSRC17,PSLC17,PSGC17,PSRC18,PSLC18,PSGC18,PSRC19,PSCC3005,PSCC3009 |  |  |  |  |  |  |
| Multi | ND | ND | Y(4) | 91 | 91 | 61011FG00-017-G |  | RES,107KOhm,+/-1%,1/16W,G,SMD0402 | KOA SPEER ELECTRONICS, INC. | RK73H1ETTP1073F | EVT | 1 | 2 | 3 | 1 | G | PLTR2 |  |  |  |  |  |  |
|  |  |  |  |  | 91 | 61011FG00-012-G |  | RES,107KOhm,+/-1%,1/16W,G,SMD0402 | WALSIN TECHNOLOGY CORPORATION | WR04X1073FTL |  | 1 | 2 | 3 |  | G |  |  |  |  |  |  |  |
|  |  |  |  |  | 91 | 61011FG00-011-G |  | RES,107KOhm,+/-1%,1/16W,G,SMD0402 | YAGEO CORPORATION COMPONENT | RC0402FR-07107KL |  | 1 | 2 | 3 |  | G |  |  |  |  |  |  |  |
|  |  |  |  |  | 91 | 61011FG00-044-G |  | RES,107KOhm,+/-1%,1/16W,G,SMD0402 | TA-I TECHNOLOGY CO., LTD. | RM04FTN1073 |  | 1 | 2 | 3 |  | G |  |  |  |  |  |  |  |
| Multi | ND | ND | Y(4) | 92 | 92 | 610118700-017-G |  | RES,51.1KOhm,+/-1%,1/16W,G,SMD0402 | KOA SPEER ELECTRONICS, INC. | RK73H1ETTP5112F | EVT | 1 | 2 | 3 | 1 | G | PLTR3 |  |  |  |  |  |  |
|  |  |  |  |  | 92 | 610118700-012-G |  | RES,51.1KOhm,+/-1%,1/16W,G,SMD0402 | WALSIN TECHNOLOGY CORPORATION | WR04X5112FTL |  | 1 | 2 | 3 |  | G |  |  |  |  |  |  |  |
|  |  |  |  |  | 92 | 610118700-011-G |  | RES,51.1KOhm,+/-1%,1/16W,G,SMD0402 | YAGEO CORPORATION COMPONENT | RC0402FR-0751K1L |  | 1 | 2 | 3 |  | G |  |  |  |  |  |  |  |
|  |  |  |  |  | 92 | 610118700-044-G |  | RES,51.1KOhm,+/-1%,1/16W,G,SMD0402 | TA-I TECHNOLOGY CO., LTD. | RM04FTN5112 |  | 1 | 2 | 3 |  | G |  |  |  |  |  |  |  |
| Multi | N |  | Y(5) | 93 | 93 | 611004M00-017-G |  | RES,16.5KOhm,+/-0.1%,1/16W,G,SMD0402 | KOA SPEER ELECTRONICS, INC. | RN731ETTP1652B25 | EVT | 1 |  | 3 | 3 | G | PLTR4,PSRR17,PSLR17 |  |  |  |  |  |  |
|  |  |  |  |  | 93 | 611004M00-024-G |  | RES,16.5KOhm,+/-0.1%,1/16W,G,SMD0402 | PANASONIC INDUSTRIAL CO.,LTD. | ERA2AEB1652X |  |  | 2 |  |  | G |  |  |  |  |  |  |  |
| Multi | N | ND | Y(4) | 94 | 94 | 610119P00-017-G | - | RES,5.11KOhm,+/-1%,1/16W,G,SMD0402 | KOA SPEER ELECTRONICS, INC. | RK73H1ETTP5111F |  | 1 | 2 | 3 | 1 | G | PLTR5 |  |  |  |  |  |  |
|  |  |  |  |  | 94 | 610119P00-012-G |  | RES,5.11KOhm,+/-1%,1/16W,G,SMD0402 | WALSIN TECHNOLOGY CORPORATION | WR04X5111FTL |  | 1 | 2 | 3 |  | G |  |  |  |  |  |  |  |
|  |  |  |  |  | 94 | 610119P00-011-G |  | RES,5.11KOhm,+/-1%,1/16W,G,SMD0402 | YAGEO CORPORATION COMPONENT | RC0402FR-075K11L | EVT | 1 | 2 | 3 |  | G |  |  |  |  |  |  |  |
|  |  |  |  |  | 94 | 610119P00-024-G |  | RES,5.11KOhm,+/-1%,1/16W,G,SMD0402 | PANASONIC INDUSTRIAL CO.,LTD. | ERJ2RKF5111X |  | 1 | 2 | 3 |  | G |  |  |  |  |  |  |  |
|  |  |  |  |  | 94 | 610119P00-029-G |  | RES,5.11KOhm,+/-1%,1/16W,G,SMD0402 | VISHAY ENTER TECHNO LOGY.INC | CRCW04025K11FKED |  | 1 | 2 | 3 |  | G |  |  |  |  |  |  |  |
| Single | N | Other | Y(1) | 95 | 95 | 320128V00-183-G |  | IC,Regulator,TPS73801DCQR,1A,ADJ,G,SOT223-5,SMD | TEXAS INSTRUMENTS | TPS73801DCQR | EVT | 1 | 2 | 3 | 1 | G | PLTU1 |  |  |  |  |  |  |
| Single | N | Other | Y(1) | 96 | 96 | 62120CM00-024-G | - | SPEA CAP,220uF,+10%~-35%,6.3V,105C,G,SMD2816,ESR<=15mOhm | PANASONIC INDUSTRIAL CO.,LTD. | EEFCX0J221YR | EVT | 1 | 2 | 3 | 2 | G | PSCCE3003,PSCCE3004 |  |  |  |  |  |  |
| Multi | N | ND | Y(3) | 97 | 97 | 62012GF00-015-G | - | CAP,22uF,+/-20%,X6S,6.3V,G,SMD0603 | MURATA ELEC. NORTH AMERICA | GRM188C80J226M | EVT | 1 | 2 | 3 | 6 | G | PSCC2,PSCC3,PSCC3000,PSCC3010,PSCC3011,PSCC3012 |  |  |  |  |  |  |
|  |  |  |  |  | 97 | 62012GF00-023-G |  | CAP,22uF,+/-20%,X6S,6.3V,G,SMD0603 | TAIYO ELECTRIC IND.CO.LTD | JDK107BC6226MA-T |  | 1 | 2 | 3 |  | G |  |  |  |  |  |  |  |
| Multi | Y | 2 | Y(3) | 98 | 98 | 620108000-015-G | - | CAP,100pF,+/-5%,NPO(C0G),50V,G,SMD0402 | MURATA ELEC. NORTH AMERICA | GRM1555C1H101J |  | 1 | 2 | 3 | 3 | G | PSCC4,PSLC14,PSGC14 |  |  |  |  |  |  |
|  |  |  |  |  | 98 | 62010800A-012-G |  | CAP,100pF,+/-5%,NPO(C0G),50V,G,SMD0402 | WALSIN TECHNOLOGY CORPORATION | 0402N101J500CT |  | 1 | 2 | 3 |  | G |  |  |  |  |  |  |  |
|  |  |  |  |  | 98 | 620108000-026-G |  | CAP,100pF,+/-5%,NPO(C0G),50V,G,SMD0402 | SAMSUNG SEMICONDUCTOR | CL05C101JB5NNNC | EVT | 1 | 2 | 3 |  | G |  |  |  |  |  |  |  |
|  |  |  |  |  | 98 | 620108000-023-G |  | CAP,100pF,+/-5%,NPO(C0G),50V,G,SMD0402 | TAIYO ELECTRIC IND.CO.LTD | UMK105CG101JV-F |  | 1 | 2 | 3 |  | G |  |  |  |  |  |  |  |
| Multi | N |  | Y(1) | 99 | 99 | 62013BS00-015-G |  | CAP,3nF,+/-10%,X7R,50V,G,SMD0402 | MURATA ELEC. NORTH AMERICA | GRM155R71H302KA01D | EVT | 1 | 2 | 3 | 1 | G | PSCC10 |  |  |  |  |  |  |
|  |  |  |  |  | 99 | 62013BS00-012-G |  | CAP,3nF,+/-10%,X7R,50V,G,SMD0402 | WALSIN TECHNOLOGY CORPORATION | 0402B302K500CT |  | 1 | 2 | 3 |  | G |  |  |  |  |  |  |  |
| Multi | Y | 2 | Y(3) | 100 | 100 | 62010FF00-015-G | - | CAP,47pF,+/-5%,NPO(C0G),50V,G,SMD0402 | MURATA ELEC. NORTH AMERICA | GRM1555C1H470J | EVT | 1 | 2 | 3 | 1 | G | PSCC11 |  |  |  |  |  |  |
|  |  |  |  |  | 100 | 62010FF06-012-G |  | CAP,47pF,+/-5%,NPO(C0G),50V,G,SMD0402 | WALSIN TECHNOLOGY CORPORATION | 0402N470J500CT |  | 1 | 2 | 3 |  | G |  |  |  |  |  |  |  |
|  |  |  |  |  | 100 | 62010FF00-026-G |  | CAP,47pF,+/-5%,NPO(C0G),50V,G,SMD0402 | SAMSUNG SEMICONDUCTOR | CL05C470JB5NNNC |  | 1 | 2 | 3 |  | G |  |  |  |  |  |  |  |
|  |  |  |  |  | 100 | 62010FF00-023-G |  | CAP,47pF,+/-5%,NPO(C0G),50V,G,SMD0402 | TAIYO ELECTRIC IND.CO.LTD | UMK105CG470JV-F |  | 1 | 2 | 3 |  | G |  |  |  |  |  |  |  |
| Multi | Y | 2 | Y(3) | 101 | 101 | 620107L00-015-G | - | CAP,2.2nF,+/-10%,X7R,50V,G,SMD0402 | MURATA ELEC. NORTH AMERICA | GRM155R71H222K | EVT | 1 | 2 | 3 | 1 | G | PSCC12 |  |  |  |  |  |  |
|  |  |  |  |  | 101 | 620107L00-012-G |  | CAP,2.2nF,+/-10%,X7R,50V,G,SMD0402 | WALSIN TECHNOLOGY CORPORATION | 0402B222K500CT |  | 1 | 2 | 3 |  | G |  |  |  |  |  |  |  |
|  |  |  |  |  | 101 | 620107L00-026-G |  | CAP,2.2nF,+/-10%,X7R,50V,G,SMD0402 | SAMSUNG SEMICONDUCTOR | CL05B222KB5NNNC |  | 1 | 2 | 3 |  | G |  |  |  |  |  |  |  |
|  |  |  |  |  | 101 | 620107L03-023-G |  | CAP,2.2nF,+/-10%,X7R,50V,G,SMD0402 | TAIYO ELECTRIC IND.CO.LTD | UMK105B7222KV-F |  | 1 | 2 | 3 |  | G |  |  |  |  |  |  |  |
| Multi | N | ND | Y(1) | 102 | 102 | 62012T300-015-G | - | CAP,1uF,+/-10%,X7S,25V,G,SMD0402 | MURATA ELEC. NORTH AMERICA | GRM155C71E105KE11D | EVT | 1 | 2 | 3 | 4 | G | PSRC4,PSLC4,PSGC4,PSCC3003 |  |  |  |  |  |  |
|  |  |  |  |  | 102 | 620138700-026-G |  | CAP,1uF,+/-10%,X6S,25V,G,SMD0402 | SAMSUNG SEMICONDUCTOR | CL05X105KA5NQNC |  | 1 | 2 | 3 |  | G |  |  |  |  |  |  |  |
|  |  |  |  |  | 102 | 620138700-015-G |  | CAP,1uF,+/-10%,X6S,25V,G,SMD0402 | MURATA ELEC. NORTH AMERICA | GRM155C81E105KE11D |  | 1 | 2 | 3 |  | G |  |  |  |  |  |  |  |
| Multi | Y |  | N | 103 | 103 | 63034FP00-088-G |  | IND,220nH@100KHz,+/-20%,23A,2.8mOhm,SHLD,G,SMD | COOPER BUSSMANN, INC. | HCM0703-R22-R | EVT | 1 |  | 3 | 1 | G | PSCL1 |  |  |  |  |  |  |
|  |  |  |  |  | 103 | 63034UP00-15A-G |  | IND,220nH@100KHz,+/-20%,23A,2.8mOhm,SHLD,G,SMD | The Inter-Technical Group, Inc. | SMHC2511-R22MHF |  |  | 2 |  |  | G |  |  |  |  |  |  |  |
| Multi | ND | ND | N | 104 | 104 | 630341400-088-G | - | IND,22nH@1MHz,+/-20%,19A,368uOhm,SHLD,G,SMD | COOPER BUSSMANN, INC. | FP0404R1-R022-R | EVT | 1 |  | 3 | 1 | G | PSCL2 |  |  |  |  |  |  |
|  |  |  |  |  | 104 | 630362G00-065-G |  | IND,22nH@100KHz,+/-20%,19A,0.32mOhm,SHLD,G,SMD | DELTA ELECTRONICS INDUSTRIAL CO.,LTD | HCB0430-220 |  |  | 2 |  |  | G |  |  |  |  |  |  |  |
| Multi | N | ND | Y(5) | 105 | 105 | 61100J300-017-G |  | RES,121 Ohm,+/-0.1%,1/16W,G,SMD0402 | KOA SPEER ELECTRONICS, INC. | RN731ETTP1210B25 | EVT | 1 |  |  | 1 | G | PSCR5 |  |  |  |  |  |  |
|  |  |  |  |  | 105 | 61100J300-011-G |  | RES,121 Ohm,+/-0.1%,1/16W,G,SMD0402 | YAGEO CORPORATION COMPONENT | RT0402BRD07121RL |  |  | 2 |  |  | G |  |  |  |  |  |  |  |
|  |  |  |  |  | 105 | 61100J300-044-G |  | RES,121Ohm,+/-0.1%,1/16W,G,SMD0402 | TA-I TECHNOLOGY CO., LTD. | RB04BTP1210 |  |  |  | 3 |  | G |  |  |  |  |  |  |  |
|  |  |  |  |  | 105 | 61100J300-012-G |  | RES,121 Ohm,+/-0.1%,1/16W,G,SMD0402 | WALSIN TECHNOLOGY CORPORATION | WF04U1210BTL |  |  |  |  |  | G |  |  |  |  |  |  |  |
| Multi | N |  | Y(5) | 106 | 106 | 61100U300-017-G |  | RES,210 Ohm,+/-0.1%,1/16W,G,SMD0402 | KOA SPEER ELECTRONICS, INC. | RN731ETTP2100B25 | EVT | 1 |  |  | 1 | G | PSCR6 |  |  |  |  |  |  |
|  |  |  |  |  | 106 | 61100U300-011-G |  | RES,210 Ohm,+/-0.1%,1/16W,G,SMD0402 | YAGEO CORPORATION COMPONENT | RT0402BRD07210RL |  |  | 2 |  |  | G |  |  |  |  |  |  |  |
|  |  |  |  |  | 106 | 61100U300-012-G |  | RES,210 Ohm,+/-0.1%,1/16W,G,SMD0402 | WALSIN TECHNOLOGY CORPORATION | WF04U2100BTL |  |  |  | 3 |  | G |  |  |  |  |  |  |  |
| Multi | ND | ND | Y(4) | 107 | 107 | 61011C400-017-G | - | RES,4.32KOhm,+/-1%,1/16W,G,SMD0402 | KOA SPEER ELECTRONICS, INC. | RK73H1ETTP4321F | EVT | 1 | 2 | 3 | 1 | G | PSCR10 |  |  |  |  |  |  |
|  |  |  |  |  | 107 | 61011C400-012-G |  | RES,4.32KOhm,+/-1%,1/16W,G,SMD0402 | WALSIN TECHNOLOGY CORPORATION | WR04X4321FTL |  | 1 | 2 | 3 |  | G |  |  |  |  |  |  |  |
|  |  |  |  |  | 107 | 61011C400-011-G |  | RES,4.32KOhm,+/-1%,1/16W,G,SMD0402 | YAGEO CORPORATION COMPONENT | RC0402FR-074K32L |  | 1 | 2 | 3 |  | G |  |  |  |  |  |  |  |
|  |  |  |  |  | 107 | 61011C400-044-G |  | RES,4.32KOhm,+/-1%,1/16W,G,SMD0402 | TA-I TECHNOLOGY CO., LTD. | RM04FTN4321 |  | 1 | 2 | 3 |  | G |  |  |  |  |  |  |  |
| Multi | N | ND | Y(4) | 108 | 108 | 610112J00-017-G | - | RES,200 Ohm,+/-1%,1/16W,G,SMD0402 | KOA SPEER ELECTRONICS, INC. | RK73H1ETTP2000F |  | 1 | 2 | 3 | 1 | G | PSCR11 |  |  |  |  |  |  |
|  |  |  |  |  | 108 | 610112J00-012-G |  | RES,200 Ohm,+/-1%,1/16W,G,SMD0402 | WALSIN TECHNOLOGY CORPORATION | WR04X2000FTL |  | 1 | 2 | 3 |  | G |  |  |  |  |  |  |  |
|  |  |  |  |  | 108 | 610112J00-011-G |  | RES,200 Ohm,+/-1%,1/16W,G,SMD0402 | YAGEO CORPORATION COMPONENT | RC0402FR-07200RL | EVT | 1 | 2 | 3 |  | G |  |  |  |  |  |  |  |
|  |  |  |  |  | 108 | 610112J00-044-G |  | RES,200 Ohm,+/-1%,1/16W,G,SMD0402 | TA-I TECHNOLOGY CO., LTD. | RM04FTN2000 |  | 1 | 2 | 3 |  | G |  |  |  |  |  |  |  |
|  |  |  |  |  | 108 | 610112J00-029-G |  | RES,200 Ohm,+/-1%,1/16W,G,SMD0402 | VISHAY ENTER TECHNO LOGY.INC | CRCW0402200RFKED |  | 1 | 2 | 3 |  | G |  |  |  |  |  |  |  |
|  |  |  |  |  | 108 | 610112J00-024-G |  | RES,200 Ohm,+/-1%,1/16W,G,SMD0402 | PANASONIC INDUSTRIAL CO.,LTD. | ERJ2RKF2000X |  | 1 | 2 | 3 |  | G |  |  |  |  |  |  |  |
| Multi | N | Other | Y(4) | 109 | 109 | 61011JY00-017-G | - | RES,39.2KOhm,+/-1%,1/16W,G,SMD0402 | KOA SPEER ELECTRONICS, INC. | RK73H1ETTP3922F |  | 1 | 2 | 3 | 1 | G | PSCR15 |  |  |  |  |  |  |
|  |  |  |  |  | 109 | 61011JY00-012-G |  | RES,39.2KOhm,+/-1%,1/16W,G,SMD0402 | WALSIN TECHNOLOGY CORPORATION | WR04X3922FTL |  | 1 | 2 | 3 |  | G |  |  |  |  |  |  |  |
|  |  |  |  |  | 109 | 61011JY00-011-G |  | RES,39.2KOhm,+/-1%,1/16W,G,SMD0402 | YAGEO CORPORATION COMPONENT | RC0402FR-0739K2L | EVT | 1 | 2 | 3 |  | G |  |  |  |  |  |  |  |
|  |  |  |  |  | 109 | 61011JY00-044-G |  | RES,39.2KOhm,+/-1%,1/16W,G,SMD0402 | TA-I TECHNOLOGY CO., LTD. | RM04FTN3922 |  | 1 | 2 | 3 |  | G |  |  |  |  |  |  |  |
|  |  |  |  |  | 109 | 61011JY00-029-G |  | RES,39.2KOhm,+/-1%,1/16W,G,SMD0402 | VISHAY ENTER TECHNO LOGY.INC | CRCW040239K2FKED |  | 1 | 2 | 3 |  | G |  |  |  |  |  |  |  |
| Multi | ND |  | Y(4) | 110 | 110 | 61011RF00-017-G |  | RES,1.8KOhm,+/-1%,1/8W,G,SMD0805 | KOA SPEER ELECTRONICS, INC. | RK73H2ATTD1801F |  | 1 | 2 | 3 | 2 | G | PSGR20,PSCR3000 |  |  |  |  |  |  |
|  |  |  |  |  | 110 | 61011RF00-011-G |  | RES,1.8KOhm,+/-1%,1/8W,G,SMD0805 | YAGEO CORPORATION COMPONENT | RC0805FR-071K8L | EVT | 1 | 2 | 3 |  | G |  |  |  |  |  |  |  |
|  |  |  |  |  | 110 | 61011RF00-012-G |  | RES,1.8KOhm,+/-1%,1/8W,G,SMD0805 | WALSIN TECHNOLOGY CORPORATION | WR08X1801FTL |  | 1 | 2 | 3 |  | G |  |  |  |  |  |  |  |
| Single | ND |  | N | 111 | 111 | 32013HH00-238-G |  | IC,Regulator,IR3447MTRPBF,ADJ,25A,G,PQFN-33 | INTERNATIONAL RECTIFIER | IR3447MTRPBF | EVT | 1 | 2 | 3 | 1 | G | PSCU1 |  |  |  |  |  |  |
| Multi | N |  | Y(3) | 112 | 112 | 62012CM01-015-G |  | CAP,10uF,+/-20%,X6S,4V,G,SMD0603 | MURATA ELEC. NORTH AMERICA | GRM188C80G106M | EVT | 1 | 2 | 3 | 2 | G | PSLC16,PSGC16 |  |  |  |  |  |  |
|  |  |  |  |  | 112 | 62012CM00-023-G |  | CAP,10uF,+/-20%,X6S,4V,G,SMD0603 | TAIYO ELECTRIC IND.CO.LTD | AMK107AC6106MA-T |  | 1 | 2 | 3 |  | G |  |  |  |  |  |  |  |
|  |  |  |  |  | 112 | 62012CM00-026-G |  | CAP,10uF,+/-20%,X6S,4V,G,SMD0603 | SAMSUNG SEMICONDUCTOR | CL10X106MR8NNNC |  | 1 | 2 | 3 |  | G |  |  |  |  |  |  |  |
| Multi | ND | ND | N | 113 | 113 | 63032CD00-088-G | - | IND,2.2uH@100KHz,+/-20%,8A,20mOhm,SHLD,G,SMD | COOPER BUSSMANN, INC. | HCM0703-2R2-R |  |  | 2 |  | 1 | G | PSGL2 |  |  |  |  |  |  |
|  |  |  |  |  | 113 | 63033JK00-15A-G |  | IND,2.2uH@100KHz,+/-20%,9A,16.5mOhm,SHLD,G,SMD | The Inter-Technical Group, Inc. | SMHC2511A-2R2MHF | EVT | 1 |  | 3 |  | G |  |  |  |  |  |  |  |
| Multi | N | ND | Y(4) | 114 | 114 | 61010G500-017-G | - | RES,10KOhm,+/-1%,1/16W,G,SMD0402 | KOA SPEER ELECTRONICS, INC. | RK73H1ETTP1002F | EVT | 1 | 2 | 3 | 62 | G | PSRR6,PSLR6,PSGR6,R18,R40,R41,R42,R43,R44,R45,R46,R89,R90,R91,R102,R103,R104,R127,R128,R129,R130,R134,R139,R141,R234,R248,R342,R343,R344,R345,R346,R347,R348,R349,R350,R351,R352,R353,R354,R355,R356,R357,R358,R359,R360,R361,R371,R397,R398,R404,R405,R406,R407,R442,R443,R1487,R1493,R1497,R1501,R1511,R1512,R1544, |  |  |  |  |  |  |
|  |  |  |  |  | 114 | 61010G500-012-G |  | RES,10KOhm,+/-1%,1/16W,G,SMD0402 | WALSIN TECHNOLOGY CORPORATION | WR04X1002FTL |  | 1 | 2 | 3 |  | G |  |  |  |  |  |  |  |
|  |  |  |  |  | 114 | 61010G500-011-G |  | RES,10KOhm,+/-1%,1/16W,G,SMD0402 | YAGEO CORPORATION COMPONENT | RC0402FR-0710KL |  | 1 | 2 | 3 |  | G |  |  |  |  |  |  |  |
|  |  |  |  |  | 114 | 61010G500-044-G |  | RES,10KOhm,+/-1%,1/16W,G,SMD0402 | TA-I TECHNOLOGY CO., LTD. | RM04FTN1002 |  | 1 | 2 | 3 |  | G |  |  |  |  |  |  |  |
|  |  |  |  |  | 114 | 61010G500-029-G |  | RES,10KOhm,+/-1%,1/16W,G,SMD0402 | VISHAY ENTER TECHNO LOGY.INC | CRCW040210K0FKED |  | 1 | 2 | 3 |  | G |  |  |  |  |  |  |  |
|  |  |  |  |  | 114 | 61010G500-024-G |  | RES,10KOhm,+/-1%,1/16W,G,SMD0402 | PANASONIC INDUSTRIAL CO.,LTD. | ERJ2RKF1002X |  | 1 | 2 | 3 |  | G |  |  |  |  |  |  |  |
| Multi | N |  | Y(5) | 115 | 115 | 61100QY00-017-G |  | RES,17.4KOhm,+/-0.1%,1/16W,G,SMD0402 | KOA SPEER ELECTRONICS, INC. | RN731ETTP1742B25 |  |  | 2 |  | 1 | G | PSGR17 |  |  |  |  |  |  |
|  |  |  |  |  | 115 | 61100QY00-011-G |  | RES,17.4KOhm,+/-0.1%,1/16W,G,SMD0402 | YAGEO CORPORATION COMPONENT | RT0402BRD0717K4L | EVT | 1 |  |  |  | G |  |  |  |  |  |  |  |
|  |  |  |  |  | 115 | 61100QY00-044-G |  | RES,17.4KOhm,+/-0.1%,1/16W,G,SMD0402 | TA-I TECHNOLOGY CO., LTD. | RB04BTP1742 |  |  |  | 3 |  | G |  |  |  |  |  |  |  |
|  |  |  |  |  | 115 | 61100QY00-012-G |  | RES,17.4KOhm,+/-0.1%,1/16W,G,SMD0402 | WALSIN TECHNOLOGY CORPORATION | WF04U1742BTL |  |  |  |  |  | G |  |  |  |  |  |  |  |
| Multi | ND |  | Y(5) | 116 | 116 | 61100PL00-017-G |  | RES,10.2KOhm,+/-0.1%,1/16W,G,SMD0402 | KOA SPEER ELECTRONICS, INC. | RN731ETTP1022B25 |  |  | 2 |  | 1 | G | PSGR19 |  |  |  |  |  |  |
|  |  |  |  |  | 116 | 61100PL00-011-G |  | RES,10.2KOhm,+/-0.1%,1/16W,G,SMD0402 | YAGEO CORPORATION COMPONENT | RT0402BRD0710K2L | EVT | 1 |  |  |  | G |  |  |  |  |  |  |  |
|  |  |  |  |  | 116 | 61100PL00-044-G |  | RES,10.2KOhm,+/-0.1%,1/16W,G,SMD0402 | TA-I TECHNOLOGY CO., LTD. | RB04BTP1022 |  |  |  | 3 |  | G |  |  |  |  |  |  |  |
|  |  |  |  |  | 116 | 61100PL00-012-G |  | RES,10.2KOhm,+/-0.1%,1/16W,G,SMD0402 | WALSIN TECHNOLOGY CORPORATION | WF04U1022BTL |  |  |  |  |  | G |  |  |  |  |  |  |  |
| Single | ND |  | N | 117 | 117 | 32013PD00-238-G |  | IC,Regulator,IR3883MTRPbF,ADJ,3A,G,QFN-16,SMD | INTERNATIONAL RECTIFIER | IR3883MTRPBF | EVT | 1 | 2 | 3 | 3 | G | PSRU1,PSLU1,PSGU1 |  |  |  |  |  |  |
| Multi | ND |  | N | 118 | 118 | 630328U00-088-G |  | IND,3.3uH@100KHz,+/-20%,6A,30mOhm,SHLD,G,SMD | COOPER BUSSMANN, INC. | HCM0703-3R3-R | EVT | 1 |  | 3 | 1 | G | PSLL2 |  |  |  |  |  |  |
|  |  |  |  |  | 118 | 63034QP00-034-G |  | IND,3.3uH@100KHz,+/-20%,6.5A,21mOhm,SHLD,G,SMD | CYNTEC CO. LTD | PCME063T-3R3MS |  |  | 2 |  |  | G |  |  |  |  |  |  |  |
| Multi | ND |  | Y(5) | 119 | 119 | 61100DF00-017-G |  | RES,6.34KOhm,+/-0.1%,1/16W,G,SMD0402 | KOA SPEER ELECTRONICS, INC. | RN731ETTP6341B25 | EVT | 1 |  |  | 1 | G | PSLR19 |  |  |  |  |  |  |
|  |  |  |  |  | 119 | 61100DF00-011-G |  | RES,6.34KOhm,+/-0.1%,1/16W,G,SMD0402 | YAGEO CORPORATION COMPONENT | RT0402BRD076K34L |  |  | 2 |  |  | G |  |  |  |  |  |  |  |
|  |  |  |  |  | 119 | 61100DF00-044-G |  | RES,6.34KOhm,+/-0.1%,1/16W,G,SMD0402 | TA-I TECHNOLOGY CO., LTD. | RB04BTP6341 |  |  |  | 3 |  | G |  |  |  |  |  |  |  |
|  |  |  |  |  | 119 | 61100DF00-024-G |  | RES,6.34KOhm,+/-0.1%,1/16W,G,SMD0402 | PANASONIC INDUSTRIAL CO.,LTD. | ERA2AEB6341X |  |  |  |  |  | G |  |  |  |  |  |  |  |
|  |  |  |  |  | 119 | 61100DF00-029-G |  | RES,6.34KOhm,+/-0.1%,1/16W,G,SMD0402 | VISHAY ENTER TECHNO LOGY.INC | TNPW04026K34BEED |  |  |  |  |  | G |  |  |  |  |  |  |  |
|  |  |  |  |  | 119 | 61100DF00-012-G |  | RES,6.34KOhm,+/-0.1%,1/16W,G,SMD0402 | WALSIN TECHNOLOGY CORPORATION | WF04U6341BTL |  |  |  |  |  | G |  |  |  |  |  |  |  |
| Multi | Y | 2 | Y(3) | 120 | 120 | 620105U00-015-G | - | CAP,220pF,+/-10%,X7R,50V,G,SMD0402 | MURATA ELEC. NORTH AMERICA | GRM155R71H221K |  | 1 | 2 | 3 | 1 | G | PSRC14 |  |  |  |  |  |  |
|  |  |  |  |  | 120 | 620105U00-012-G |  | CAP,220pF,+/-10%,X7R,50V,G,SMD0402 | WALSIN TECHNOLOGY CORPORATION | 0402B221K500CT |  | 1 | 2 | 3 |  | G |  |  |  |  |  |  |  |
|  |  |  |  |  | 120 | 620105U00-026-G |  | CAP,220pF,+/-10%,X7R,50V,G,SMD0402 | SAMSUNG SEMICONDUCTOR | CL05B221KB5NNNC | EVT | 1 | 2 | 3 |  | G |  |  |  |  |  |  |  |
| Multi | N |  | N | 121 | 121 | 63032PP00-088-G |  | IND,4.7uH@100KHz,+/-20%,5.5A,40mOhm,SHLD,G,SMD | COOPER BUSSMANN, INC. | HCM0703-4R7-R | EVT | 1 |  |  | 1 | G | PSRL2 |  |  |  |  |  |  |
|  |  |  |  |  | 121 | 63030PW00-034-G |  | Coil Ind,Shielded(SHLD),4.7uH@100KHz,+/-20%,5.5A,40mOhm,SMD,7.3*6.6*3.0,G | CYNTEC CO. LTD | PCMC063T-4R7MN |  |  | 2 |  |  | G |  |  |  |  |  |  |  |
|  |  |  |  |  | 121 | 63031AD04-129-G |  | IND,4.7uH@100KHz,+/-20%,5.5A,40mOhm,SHLD,G,SMD | MAG.LAYERS, SCIENTIFIC-TECHNICS (KUNSHAN) CO., LTD. | SPS-06CZ-4R7M-V1 | EVT |  |  | 3 |  | G |  |  |  |  |  |  |  |
| Multi | ND | ND | Y(4) | 122 | 122 | 610117D00-017-G | - | RES,13.3KOhm,+/-1%,1/16W,G,SMD0402 | KOA SPEER ELECTRONICS, INC. | RK73H1ETTP1332F | EVT | 1 | 2 | 3 | 1 | G | PSRR1 |  |  |  |  |  |  |
|  |  |  |  |  | 122 | 610117D00-012-G |  | RES,13.3KOhm,+/-1%,1/16W,G,SMD0402 | WALSIN TECHNOLOGY CORPORATION | WR04X1332FTL |  | 1 | 2 | 3 |  | G |  |  |  |  |  |  |  |
|  |  |  |  |  | 122 | 610117D00-011-G |  | RES,13.3KOhm,+/-1%,1/16W,G,SMD0402 | YAGEO CORPORATION COMPONENT | RC0402FR-0713K3L |  | 1 | 2 | 3 |  | G |  |  |  |  |  |  |  |
|  |  |  |  |  | 122 | 610117D00-044-G |  | RES,13.3KOhm,+/-1%,1/16W,G,SMD0402 | TA-I TECHNOLOGY CO., LTD. | RM04FTN1332 |  | 1 | 2 | 3 |  | G |  |  |  |  |  |  |  |
| Multi | N |  | Y(5) | 123 | 123 | 61100YB00-017-G |  | RES,2.94KOhm,+/-0.1%,1/16W,G,SMD0402 | KOA SPEER ELECTRONICS, INC. | RN731ETTP2941B25 | EVT | 1 |  |  | 1 | G | PSRR19 |  |  |  |  |  |  |
|  |  |  |  |  | 123 | 61100YB00-011-G |  | RES,2.94KOhm,+/-0.1%,1/16W,G,SMD0402 | YAGEO CORPORATION COMPONENT | RT0402BRD072K94L |  |  | 2 |  |  | G |  |  |  |  |  |  |  |
|  |  |  |  |  | 123 | 61100YB00-044-G |  | RES,2.94KOhm,+/-0.1%,1/16W,G,SMD0402 | TA-I TECHNOLOGY CO., LTD | RB04BTP2941 |  |  |  | 3 |  | G |  |  |  |  |  |  |  |
| Multi | ND | ND | N | 124 | 124 | 510503B00-223-G |  | MOS N/N,NTZD3154NT1G,20V,0.54A,550m24.5V,G,SOT563-6,SMD | ON SEMICONDUCTOR CORP | NTZD3154NT1G | EVT | 1 |  |  | 4 | G | QN1,QN2,QN3,QN5 |  |  |  |  |  |  |
|  |  |  |  |  | 124 | 51050L500-029-G |  | MOS,N/N,Si1034CX-T1-GE3,20V,0.61A,G,SC-89-6,SMD | VISHAY ENTER TECHNO LOGY.INC | Si1034CX-T1-GE3 |  |  | 2 |  |  | G |  |  |  |  |  |  |  |
|  |  |  |  |  | 124 | 51050KW00-131-G |  | MOS N/N,SSM6N36FE,20V,500mA,0.63@5V,G,ES6-6,SMD | TOSHIBA ELECTRONICS ASIA LTD | SSM6N36FE |  |  |  | 3 |  | G |  |  |  |  |  |  |  |
| Multi | ND | ND | N | 125 | 125 | 510501900-237-G | - | MOS N/N,2N7002DW-7-F,60V,0.115A,7.5ohm@5V,G,SOT363-6,SMD | DIODES INEORPORATION | 2N7002DW-7-F | EVT | 1 |  |  | 1 | G | QN4 |  |  |  |  |  |  |
|  |  |  |  |  | 125 | 51050HV00-031-G |  | FET Dual channel,NX7002BKS,60V,240mA,2.8Ohm@Vgs=10V,3.2Ohm@Vgs=5V,SOT-363,6P,G | NXP SEMICONDUCTORS | NX7002BKS |  |  | 2 |  |  | G |  |  |  |  |  |  |  |
|  |  |  |  |  | 125 | 510329S00-131-G |  | MOS N,SSM6N7002KFU,LF(T,60V,300mA,1.5@10V,G,US6-6,SMD | TOSHIBA ELECTRONICS ASIA LTD | SSM6N7002KFU,LF(T |  |  |  | 3 |  | G |  |  |  |  |  |  |  |
| Multi | ND | ND | N | 126 | 126 | 510302R00-185-G |  | MOS N,BSS138,50V,0.22A,6ohm@4.5V,G,SOT23-3,SMD | FAIRCHILD SEMICONDUCTOR CORP | BSS138 |  |  | 2 |  | 5 | G | Q1,Q2,Q3,Q8,Q9 |  |  |  |  |  |  |
|  |  |  |  |  | 126 | 510309C00-237-G |  | MOS N,BSS138-7-F,50V,0.2A,3.5ohm@10V,G,SOT23-3,SMD | DIODES INCORPORATION | BSS138-7-F | EVT | 1 |  |  |  | G |  |  |  |  |  |  |  |
|  |  |  |  |  | 126 | 510301D00-223-G |  | MOS N,BSS138LT1G,50V,0.2A,3.5ohm@5V,G,SOT23-3,SMD | ON SEMICONDUCTOR CORP | BSS138LT1G | EVT |  |  | 3 |  | G |  |  |  |  |  |  |  |
| Multi | Y |  | N | 127 | 127 | 51040EK00-185-G |  | MOS P,FDMS6681Z,30V,49A,5m@4.5V,G,Power56-8,SMD | FAIRCHILD SEMICONDUCTOR CORP | FDMS6681Z | EVT | 1 |  |  | 2 | G | Q4,Q6 |  |  |  |  |  |  |
|  |  |  |  |  | 127 | 51040ME00-262-G |  | MOS P,AON6403L,30V,85A,4.3m@4.5V,G,DFN-8,SMD | Alpha & Omega Semiconductor Inc. | AON6403L |  |  | 2 |  |  | G |  |  |  |  |  |  |  |
|  |  |  |  |  | 127 | 51040MH00-221-G |  | MOS P,BSC030P03NS3 G,30V,100A,4.6m@6V,G,TDSON-8,SMD | INFINEON TECHNOLOGIES CORP. | BSC030P03NS3 G |  |  |  | 3 |  | G |  |  |  |  |  |  |  |
| Multi | ND | ND | Y(3) | 128 | 128 | 51030S400-185-G |  | MOS N,FDMC8884,30V,9A,30m@4.5V,G,Power33-8,SMD | FAIRCHILD SEMICONDUCTOR CORP | FDMC8884 | EVT | 1 |  |  | 1 | G | Q5 |  |  |  |  |  |  |
|  |  |  |  |  | 128 | 51031D300-221-G |  | MOS N,BSZ0909NS,34V,36A,15m@4.5V,G,SON-8,SMD | INFINEON TECHNOLOGIES CORP. | BSZ0909NS |  |  | 2 |  |  |  |  |  |  |  |  |  |  |
|  |  |  |  |  | 128 | 51030SM00-029-G |  | MOSFET-N,SIS412DN-T1-GE3,30V,12A,24mOhm@Vgs=10V,30mOhm@Vgs=4.5V,PowerPAK1212,8P,G | VISHAY ENTER TECHNO LOGY.INC | SIS412DN-T1-GE3 |  |  |  | 3 |  | G |  |  |  |  |  |  |  |
|  |  |  |  |  | 128 | 51031BT00-223-G |  | MOS N,NTTFS4930NTAG,30V,7.2A,30m@4.5V,G,WDFN-8,SMD | ON SEMICONDUCTOR CORP | NTTFS4930NTAG |  |  |  |  |  | G |  |  |  |  |  |  |  |
| Multi | ND | ND | N | 129 | 129 | 510301N00-223-G |  | MOS N,2N7002LT1G,60V,0.115A,7.5ohm@5V,G,SOT23-3,SMD | ON SEMICONDUCTOR CORP | 2N7002LT1G |  |  | 2 |  | 1 | G | Q7 |  |  |  |  |  |  |
|  |  |  |  |  | 129 | 51030CQ00-185-G |  | MOS N,2N7002,60V,115mA,7.5ohm@5V,G,SOT23-3,SMD | FAIRCHILD SEMICONDUCTOR CORP | 2N7002 | EVT | 1 |  | 3 |  | G |  |  |  |  |  |  |  |
| Multi | ND | ND | Y(4) | 130 | 130 | 61010H800-017-G |  | RES,5.11 Ohm,+/-1%,1/10W,G,SMD0603 | KOA SPEER ELECTRONICS, INC. | RK73H1JTTD5R11F |  | 1 | 2 | 3 | 1 | G | R4 |  |  |  |  |  |  |
|  |  |  |  |  | 130 | 61010H800-012-G |  | RES,5.11 Ohm,+/-1%,1/10W,G,SMD0603 | WALSIN TECHNOLOGY CORPORATION | WR06W5R11FTL |  | 1 | 2 | 3 |  | G |  |  |  |  |  |  |  |
|  |  |  |  |  | 130 | 61010H800-011-G |  | RES,5.11 Ohm,+/-1%,1/10W,G,SMD0603 | YAGEO CORPORATION COMPONENT | RC0603FR-075R11L | EVT | 1 | 2 | 3 |  | G |  |  |  |  |  |  |  |
|  |  |  |  |  | 130 | 61010H800-044-G |  | RES,5.11 Ohm,+/-1%,1/10W,G,SMD0603 | TA-I TECHNOLOGY CO., LTD. | RM06FTN5R11 |  | 1 | 2 | 3 |  | G |  |  |  |  |  |  |  |
| Multi | N | Other | Y(4) | 131 | 131 | 61011MQ00-017-G | - | RES,4.75KOhm,+/-1%,1/16W,G,SMD0402 | KOA SPEER ELECTRONICS, INC. | RK73H1ETTP4751F |  | 1 | 2 | 3 | 15 | G | R5,R28,R30,R34,R36,R78,R84,R92,R188,R195,R210,R211,R241,R242,R1446 |  |  |  |  |  |  |
|  |  |  |  |  | 131 | 61011MQ00-011-G |  | RES,4.75KOhm,+/-1%,1/16W,G,SMD0402 | YAGEO CORPORATION COMPONENT | RC0402FR-074K75L |  | 1 | 2 | 3 |  | G |  |  |  |  |  |  |  |
|  |  |  |  |  | 131 | 61011MQ00-012-G |  | RES,4.75KOhm,+/-1%,1/16W,G,SMD0402 | WALSIN TECHNOLOGY CORPORATION | WR04X4751FTL | EVT | 1 | 2 | 3 |  | G |  |  |  |  |  |  |  |
|  |  |  |  |  | 131 | 61011MQ00-044-G |  | RES,4.75KOhm,+/-1%,1/16W,G,SMD0402 | TA-I TECHNOLOGY CO., LTD. | RM04FTN4751 |  | 1 | 2 | 3 |  | G |  |  |  |  |  |  |  |
| Multi | ND | ND | Y(4) | 132 | 132 | 61011KB00-017-G | - | RES,51.1 Ohm,+/-1%,1/16W,G,SMD0402 | KOA SPEER ELECTRONICS, INC. | RK73H1ETTP51R1F | EVT | 1 | 2 | 3 | 4 | G | R6,R8,R9,R10 |  |  |  |  |  |  |
|  |  |  |  |  | 132 | 61011KB00-011-G |  | RES,51.1 Ohm,+/-1%,1/16W,G,SMD0402 | YAGEO CORPORATION COMPONENT | RC0402FR-0751R1L |  | 1 | 2 | 3 |  | G |  |  |  |  |  |  |  |
|  |  |  |  |  | 132 | 61011KB00-012-G |  | RES,51.1 Ohm,+/-1%,1/16W,G,SMD0402 | WALSIN TECHNOLOGY CORPORATION | WR04X51R1FTL |  | 1 | 2 | 3 |  | G |  |  |  |  |  |  |  |
|  |  |  |  |  | 132 | 61011KB00-044-G |  | RES,51.1 Ohm,+/-1%,1/16W,G,SMD0402 | TA-I TECHNOLOGY CO., LTD. | RM04FTN51R1 |  | 1 | 2 | 3 |  | G |  |  |  |  |  |  |  |
| Multi | ND | ND | Y(4) | 133 | 133 | 61011BH00-017-G |  | RES,22.1 Ohm,+/-1%,1/16W,G,SMD0402 | KOA SPEER ELECTRONICS, INC. | RK73H1ETTP22R1F |  | 1 | 2 | 3 | 3 | G | R12,R13,R136 |  |  |  |  |  |  |
|  |  |  |  |  | 133 | 61011BH00-012-G |  | RES,22.1 Ohm,+/-1%,1/16W,G,SMD0402 | WALSIN TECHNOLOGY CORPORATION | WR04X22R1FTL | EVT | 1 | 2 | 3 |  | G |  |  |  |  |  |  |  |
|  |  |  |  |  | 133 | 61011BH00-011-G |  | RES,22.1 Ohm,+/-1%,1/16W,G,SMD0402 | YAGEO CORPORATION COMPONENT | RC0402FR-0722R1L |  | 1 | 2 | 3 |  | G |  |  |  |  |  |  |  |
|  |  |  |  |  | 133 | 61011BH00-044-G |  | RES,22.1 Ohm,+/-1%,1/16W,G,SMD0402 | TA-I TECHNOLOGY CO., LTD. | RM04FTN22R1 |  | 1 | 2 | 3 |  | G |  |  |  |  |  |  |  |
| Multi | N | ND | Y(4) | 134 | 134 | 61011M600-017-G |  | RES,82.5 Ohm,+/-1%,1/16W,G,SMD0402 | KOA SPEER ELECTRONICS, INC. | RK73H1ETTP82R5F | EVT | 1 | 2 | 3 | 1 | G | R14 |  |  |  |  |  |  |
|  |  |  |  |  | 134 | 61011M600-011-G |  | RES,82.5 Ohm,+/-1%,1/16W,G,SMD0402 | YAGEO CORPORATION COMPONENT | RC0402FR-0782R5L |  | 1 | 2 | 3 |  | G |  |  |  |  |  |  |  |
|  |  |  |  |  | 134 | 61011M600-012-G |  | RES,82.5 Ohm,+/-1%,1/16W,G,SMD0402 | WALSIN TECHNOLOGY CORPORATION | WR04X82R5FTL |  | 1 | 2 | 3 |  | G |  |  |  |  |  |  |  |
| Multi |  |  | Y(4) | 135 | 135 | 610112W00-017-G |  | RES,2KOhm,+/-5%,1/16W,G,SMD0402 | KOA SPEER ELECTRONICS, INC. | RK73B1ETTP202J |  | 1 | 2 | 3 | 37 | G | R15,R17,R27,R29,R38,R39,R48,R49,R50,R51,R53,R54,R55,R57,R58,R59,R60,R61,R62,R63,R64,R65,R66,R67,R68,R69,R79,R80,R81,R82,R83,R87,R93,R95,R97,R98,R99 |  |  |  |  |  |  |
|  |  |  |  |  | 135 | 610112W00-012-G |  | RES,2KOhm,+/-5%,1/16W,G,SMD0402 | WALSIN TECHNOLOGY CORPORATION | WR04X202JTL | EVT | 1 | 2 | 3 |  | G |  |  |  |  |  |  |  |
|  |  |  |  |  | 135 | 610112W00-011-G |  | RES,2KOhm,+/-5%,1/16W,G,SMD0402 | YAGEO CORPORATION COMPONENT | RC0402JR-072KL |  | 1 | 2 | 3 |  | G |  |  |  |  |  |  |  |
|  |  |  |  |  | 135 | 610112W00-044-G |  | RES,2KOhm,+/-5%,1/16W,G,SMD0402 | TA-I TECHNOLOGY CO., LTD. | RM04JTN202 |  | 1 | 2 | 3 |  | G |  |  |  |  |  |  |  |
|  |  |  |  |  | 135 | 610112W00-024-G |  | RES,2KOhm,+/-5%,1/16W,G,SMD0402 | PANASONIC INDUSTRIAL CO.,LTD. | ERJ2GEJ202X |  | 1 | 2 | 3 |  | G |  |  |  |  |  |  |  |
| Multi | N | Other | Y(4) | 136 | 136 | 610114E00-017-G |  | RES,33.2 Ohm,+/-1%,1/16W,G,SMD0402 | KOA SPEER ELECTRONICS, INC. | RK73H1ETTP33R2F | EVT | 1 | 2 | 3 | 1 | G | R16 |  |  |  |  |  |  |
|  |  |  |  |  | 136 | 610114E00-012-G |  | RES,33.2 Ohm,+/-1%,1/16W,G,SMD0402 | WALSIN TECHNOLOGY CORPORATION | WR04X33R2FTL |  | 1 | 2 | 3 |  | G |  |  |  |  |  |  |  |
|  |  |  |  |  | 136 | 610114E00-011-G |  | RES,33.2 Ohm,+/-1%,1/16W,G,SMD0402 | YAGEO CORPORATION COMPONENT | RC0402FR-0733R2L |  | 1 | 2 | 3 |  | G |  |  |  |  |  |  |  |
|  |  |  |  |  | 136 | 610114E00-044-G |  | RES,33.2 Ohm,+/-1%,1/16W,G,SMD0402 | TA-I TECHNOLOGY CO., LTD. | RM04FTN33R2 |  | 1 | 2 | 3 |  | G |  |  |  |  |  |  |  |
| Multi | N | ND | Y(4) | 137 | 137 | 610114J00-017-G | - | RES,2KOhm,+/-1%,1/16W,G,SMD0402 | KOA SPEER ELECTRONICS, INC. | RK73H1ETTP2001F |  | 1 | 2 | 3 | 1 | G | R26 |  |  |  |  |  |  |
|  |  |  |  |  | 137 | 610114J00-012-G |  | RES,2KOhm,+/-1%,1/16W,G,SMD0402 | WALSIN TECHNOLOGY CORPORATION | WR04X2001FTL |  | 1 | 2 | 3 |  | G |  |  |  |  |  |  |  |
|  |  |  |  |  | 137 | 610114J00-011-G |  | RES,2KOhm,+/-1%,1/16W,G,SMD0402 | YAGEO CORPORATION COMPONENT | RC0402FR-072KL |  | 1 | 2 | 3 |  | G |  |  |  |  |  |  |  |
|  |  |  |  |  | 137 | 610114J00-044-G |  | RES,2KOhm,+/-1%,1/16W,G,SMD0402 | TA-I TECHNOLOGY CO., LTD. | RM04FTN2001 | EVT | 1 | 2 | 3 |  | G |  |  |  |  |  |  |  |
|  |  |  |  |  | 137 | 610114J00-024-G |  | RES,2KOhm,+/-1%,1/16W,G,SMD0402 | PANASONIC INDUSTRIAL CO.,LTD. | ERJ2RKF2001X |  | 1 | 2 | 3 |  | G |  |  |  |  |  |  |  |
|  |  |  |  |  | 137 | 610114J00-029-G |  | RES,2KOhm,+/-1%,1/16W,G,SMD0402 | VISHAY ENTER TECHNO LOGY.INC | CRCW04022K00FKED |  | 1 | 2 | 3 |  | G |  |  |  |  |  |  |  |
| Multi | N | Other | Y(4) | 138 | 138 | 61010JY00-017-G | - | RES,220 Ohm,+/-5%,1/16W,G,SMD0402 | KOA SPEER ELECTRONICS, INC. | RK73B1ETTP221J |  | 1 | 2 | 3 | 5 | G | R192,R194,R200,R201,R203 |  |  |  |  |  |  |
|  |  |  |  |  | 138 | 61010JY00-012-G |  | RES,220 Ohm,+/-5%,1/16W,G,SMD0402 | WALSIN TECHNOLOGY CORPORATION | WR04X221JTL | EVT | 1 | 2 | 3 |  | G |  |  |  |  |  |  |  |
|  |  |  |  |  | 138 | 61010JY00-011-G |  | RES,220 Ohm,+/-5%,1/16W,G,SMD0402 | YAGEO CORPORATION COMPONENT | RC0402JR-07220RL | EVT | 1 | 2 | 3 |  | G |  |  |  |  |  |  |  |
|  |  |  |  |  | 138 | 61010JY00-044-G |  | RES,220 Ohm,+/-5%,1/16W,G,SMD0402 | TA-I TECHNOLOGY CO., LTD. | RM04JTN221 |  | 1 | 2 | 3 |  | G |  |  |  |  |  |  |  |
| Multi | ND | ND | Y(4) | 139 | 139 | 61012RW00-017-G |  | RES,510mOhm,+/-1%,1/8W,G,SMD0402 | KOA SPEER ELECTRONICS, INC. | SR731ETTPR510F | EVT | 1 | 2 | 3 | 12 | G | R115,R116,R117,R118,R119,R120,R121,R122,R123,R124,R125,R126 |  |  |  |  |  |  |
|  |  |  |  |  | 139 | 61012RW00-011-G |  | RES,510mOhm,+/-1%,1/8W,G,SMD0402 | YAGEO CORPORATION COMPONENT | PT0402FR-7W0R51L |  | 1 | 2 | 3 |  | G |  |  |  |  |  |  |  |
|  |  |  |  |  | 139 | 61012RW00-012-G |  | RES,510mOhm,+/-1%,1/8W,G,SMD0402 | WALSIN TECHNOLOGY CORPORATION | WW04PR510FTL |  | 1 | 2 | 3 |  | G |  |  |  |  |  |  |  |
| Multi | ND | ND | Y(4) | 140 | 140 | 61011T000-017-G |  | RES,82 Ohm,+/-1%,1/16W,G,SMD0402 | KOA SPEER ELECTRONICS, INC. | RK73H1ETTP82R0F | EVT | 1 | 2 | 3 | 42 | G | R143,R144,R145,R146,R147,R148,R149,R150,R151,R152,R153,R154,R155,R156,R157,R158,R159,R160,R161,R162,R163,R164,R165,R166,R167,R168,R169,R170,R171,R172,R173,R174,R175,R177,R178,R179,R180,R181,R182,R183,R184,R185 |  |  |  |  |  |  |
|  |  |  |  |  | 140 | 61011T000-011-G |  | RES,82 Ohm,+/-1%,1/16W,G,SMD0402 | YAGEO CORPORATION COMPONENT | RC0402FR-0782RL |  | 1 | 2 | 3 |  | G |  |  |  |  |  |  |  |
|  |  |  |  |  | 140 | 61011T000-012-G |  | RES,82 Ohm,+/-1%,1/16W,G,SMD0402 | WALSIN TECHNOLOGY CORPORATION | WR04X82R0FTL |  | 1 | 2 | 3 |  | G |  |  |  |  |  |  |  |
|  |  |  |  |  | 140 | 61011T000-044-G |  | RES,82 Ohm,+/-1%,1/16W,G,SMD0402 | TA-I TECHNOLOGY CO., LTD. | RM04FTN82R0 |  | 1 | 2 | 3 |  | G |  |  |  |  |  |  |  |
| Multi | N | ND | Y(4) | 141 | 141 | 610101V00-017-G | K9572 | RES,22 Ohm,+/-5%,1/16W,G,SMD0402 | KOA SPEER ELECTRONICS, INC. | RK73B1ETTP220J |  | 1 | 2 | 3 | 1 | G | R190 |  |  |  |  |  |  |
|  |  |  |  |  | 141 | 610101V00-012-G |  | RES,22 Ohm,+/-5%,1/16W,G,SMD0402 | WALSIN TECHNOLOGY CORPORATION | WR04X220JTL |  | 1 | 2 | 3 |  | G |  |  |  |  |  |  |  |
|  |  |  |  |  | 141 | 610101V00-011-G |  | RES,22 Ohm,+/-5%,1/16W,G,SMD0402 | YAGEO CORPORATION COMPONENT | RC0402JR-0722RL | EVT | 1 | 2 | 3 |  | G |  |  |  |  |  |  |  |
|  |  |  |  |  | 141 | 610101V00-044-G |  | RES,22 Ohm,+/-5%,1/16W,G,SMD0402 | TA-I TECHNOLOGY CO., LTD. | RM04JTN220 |  | 1 | 2 | 3 |  | G |  |  |  |  |  |  |  |
|  |  |  |  |  | 141 | 610101V00-024-G |  | RES,22 Ohm,+/-5%,1/16W,G,SMD0402 | PANASONIC INDUSTRIAL CO.,LTD. | ERJ2GEJ220X |  | 1 | 2 | 3 |  | G |  |  |  |  |  |  |  |
| Multi | ND | ND | Y(4) | 142 | 142 | 61011H500-017-G | - | RES,22 Ohm,+/-1%,1/16W,G,SMD0402 | KOA SPEER ELECTRONICS, INC. | RK73H1ETTP22R0F |  | 1 | 2 | 3 | 1 | G | R202 |  |  |  |  |  |  |
|  |  |  |  |  | 142 | 61011H500-012-G |  | RES,22 Ohm,+/-1%,1/16W,G,SMD0402 | WALSIN TECHNOLOGY CORPORATION | WR04X22R0FTL | EVT | 1 | 2 | 3 |  | G |  |  |  |  |  |  |  |
|  |  |  |  |  | 142 | 61011H500-011-G |  | RES,22 Ohm,+/-1%,1/16W,G,SMD0402 | YAGEO CORPORATION COMPONENT | RC0402FR-0722RL |  | 1 | 2 | 3 |  | G |  |  |  |  |  |  |  |
|  |  |  |  |  | 142 | 61011H500-044-G |  | RES,22 Ohm,+/-1%,1/16W,G,SMD0402 | TA-I TECHNOLOGY CO., LTD. | RM04FTN22R0 |  | 1 | 2 | 3 |  | G |  |  |  |  |  |  |  |
|  |  |  |  |  | 142 | 61011H500-024-G |  | RES,22 Ohm,+/-1%,1/16W,G,SMD0402 | PANASONIC INDUSTRIAL CO.,LTD. | ERJ2RKF22R0X |  | 1 | 2 | 3 |  | G |  |  |  |  |  |  |  |
| Multi | N | other | Y(4) | 143 | 143 | 610100T00-017-G |  | RES,1KOhm,+/-5%,1/16W,G,SMD0402 | KOA SPEER ELECTRONICS, INC. | RK73B1ETTP102J | EVT | 1 | 2 | 3 | 7 | G | R208,R209,R218,R219,R224,R225,R1510 |  |  |  |  |  |  |
|  |  |  |  |  | 143 | 610100T00-012-G |  | RES,1KOhm,+/-5%,1/16W,G,SMD0402 | WALSIN TECHNOLOGY CORPORATION | WR04X102JTL |  | 1 | 2 | 3 |  | G |  |  |  |  |  |  |  |
|  |  |  |  |  | 143 | 610100T00-011-G |  | RES,1KOhm,+/-5%,1/16W,G,SMD0402 | YAGEO CORPORATION COMPONENT | RC0402JR-071KL | EVT | 1 | 2 | 3 |  | G |  |  |  |  |  |  |  |
|  |  |  |  |  | 143 | 610100T00-044-G |  | RES,1KOhm,+/-5%,1/16W,G,SMD0402 | TA-I TECHNOLOGY CO., LTD. | RM04JTN102 |  | 1 | 2 | 3 |  | G |  |  |  |  |  |  |  |
|  |  |  |  |  | 143 | 610100T00-024-G |  | RES,1KOhm,+/-5%,1/16W,G,SMD0402 | PANASONIC INDUSTRIAL CO.,LTD. | ERJ2GEJ102X |  | 1 | 2 | 3 |  | G |  |  |  |  |  |  |  |
| Multi | N | ND | Y(4) | 144 | 144 | 610107B00-017-G | K9576 | RES,4.7KOhm,+/-5%,1/16W,G,SMD0402 | KOA SPEER ELECTRONICS, INC. | RK73B1ETTP472J |  | 1 | 2 | 3 | 4 | G | R228,R1415,R1440,R1517 |  |  |  |  |  |  |
|  |  |  |  |  | 144 | 610107B00-012-G |  | RES,4.7KOhm,+/-5%,1/16W,G,SMD0402 | WALSIN TECHNOLOGY CORPORATION | WR04X472JTL | EVT | 1 | 2 | 3 |  | G |  |  |  |  |  |  |  |
|  |  |  |  |  | 144 | 610107B00-011-G |  | RES,4.7KOhm,+/-5%,1/16W,G,SMD0402 | YAGEO CORPORATION COMPONENT | RC0402JR-074K7L | EVT | 1 | 2 | 3 |  | G |  |  |  |  |  |  |  |
|  |  |  |  |  | 144 | 610107B00-044-G |  | RES,4.7KOhm,+/-5%,1/16W,G,SMD0402 | TA-I TECHNOLOGY CO., LTD. | RM04JTN472 |  | 1 | 2 | 3 |  | G |  |  |  |  |  |  |  |
|  |  |  |  |  | 144 | 610107B00-024-G |  | RES,4.7KOhm,+/-5%,1/16W,G,SMD0402 | PANASONIC INDUSTRIAL CO.,LTD. | ERJ2GEJ472X |  | 1 | 2 | 3 |  | G |  |  |  |  |  |  |  |
|  |  |  |  |  | 144 | 610107B00-029-G |  | RES,4.7KOhm,+/-5%,1/16W,G,SMD0402 | VISHAY ENTER TECHNO LOGY.INC | CRCW04024K70JNED |  | 1 | 2 | 3 |  | G |  |  |  |  |  |  |  |
| Multi | ND | ND | Y(4) | 145 | 145 | 61010L100-017-G | - | RES,100KOhm,+/-1%,1/16W,G,SMD0402 | KOA SPEER ELECTRONICS, INC. | RK73H1ETTP1003F |  | 1 | 2 | 3 | 3 | G | R233,R238,R245 |  |  |  |  |  |  |
|  |  |  |  |  | 145 | 61010L100-012-G |  | RES,100KOhm,+/-1%,1/16W,G,SMD0402 | WALSIN TECHNOLOGY CORPORATION | WR04X1003FTL |  | 1 | 2 | 3 |  | G |  |  |  |  |  |  |  |
|  |  |  |  |  | 145 | 61010L100-011-G |  | RES,100KOhm,+/-1%,1/16W,G,SMD0402 | YAGEO CORPORATION COMPONENT | RC0402FR-07100KL | EVT | 1 | 2 | 3 |  | G |  |  |  |  |  |  |  |
|  |  |  |  |  | 145 | 61010L100-044-G |  | RES,100KOhm,+/-1%,1/16W,G,SMD0402 | TA-I TECHNOLOGY CO., LTD. | RM04FTN1003 |  | 1 | 2 | 3 |  | G |  |  |  |  |  |  |  |
|  |  |  |  |  | 145 | 61010L106-029-G |  | RES,100KOhm,+/-1%,1/16W,G,SMD0402 | VISHAY ENTER TECHNO LOGY.INC | CRCW0402100KFKEDC |  | 1 | 2 | 3 |  | G |  |  |  |  |  |  |  |
|  |  |  |  |  | 145 | 61010L100-024-G |  | RES,100KOhm,+/-1%,1/16W,G,SMD0402 | PANASONIC INDUSTRIAL CO.,LTD. | ERJ2RKF1003X |  | 1 | 2 | 3 |  | G |  |  |  |  |  |  |  |
| Multi | ND | ND | Y(4) | 146 | 146 | 61011WQ00-017-G | - | RES,3KOhm,+/-1%,1/16W,G,SMD0402 | KOA SPEER ELECTRONICS, INC. | RK73H1ETTP3001F | EVT | 1 | 2 | 3 | 56 | G | R255,R256,R257,R258,R259,R260,R261,R262,R263,R268,R269,R270,R271,R272,R273,R274,R275,R276,R281,R282,R283,R284,R285,R286,R287,R288,R289,R297,R298,R299,R300,R301,R302,R303,R304,R305,R310,R311,R312,R313,R314,R315,R316,R317,R318,R326,R327,R328,R329,R330,R331,R332,R333,R334,R383,R384 |  |  |  |  |  |  |
|  |  |  |  |  | 146 | 61011WQ00-012-G |  | RES,3KOhm,+/-1%,1/16W,G,SMD0402 | WALSIN TECHNOLOGY CORPORATION | WR04X3001FTL |  | 1 | 2 | 3 |  | G |  |  |  |  |  |  |  |
|  |  |  |  |  | 146 | 61011WQ00-011-G |  | RES,3KOhm,+/-1%,1/16W,G,SMD0402 | YAGEO CORPORATION COMPONENT | RC0402FR-073KL |  | 1 | 2 | 3 |  | G |  |  |  |  |  |  |  |
|  |  |  |  |  | 146 | 61011WQ00-044-G |  | RES,3KOhm,+/-1%,1/16W,G,SMD0402 | TA-I TECHNOLOGY CO., LTD. | RM04FTN3001 |  | 1 | 2 | 3 |  | G |  |  |  |  |  |  |  |
| Multi | ND | ND | Y(4) | 147 | 147 | 61011B000-017-G | - | RES,1.5KOhm,+/-1%,1/16W,G,SMD0402 | KOA SPEER ELECTRONICS, INC. | RK73H1ETTP1501F |  | 1 | 2 | 3 | 1 | G | R382 |  |  |  |  |  |  |
|  |  |  |  |  | 147 | 61011B000-012-G |  | RES,1.5KOhm,+/-1%,1/16W,G,SMD0402 | WALSIN TECHNOLOGY CORPORATION | WR04X1501FTL |  | 1 | 2 | 3 |  | G |  |  |  |  |  |  |  |
|  |  |  |  |  | 147 | 61011B000-011-G |  | RES,1.5KOhm,+/-1%,1/16W,G,SMD0402 | YAGEO CORPORATION COMPONENT | RC0402FR-071K5L | EVT | 1 | 2 | 3 |  | G |  |  |  |  |  |  |  |
|  |  |  |  |  | 147 | 61011B000-044-G |  | RES,1.5KOhm,+/-1%,1/16W,G,SMD0402 | TA-I TECHNOLOGY CO., LTD. | RM04FTN1501 |  | 1 | 2 | 3 |  | G |  |  |  |  |  |  |  |
|  |  |  |  |  | 147 | 61011B000-024-G |  | RES,1.5KOhm,+/-1%,1/16W,G,SMD0402 | PANASONIC INDUSTRIAL CO.,LTD. | ERJ2RKF1501X |  | 1 | 2 | 3 |  | G |  |  |  |  |  |  |  |
| Multi | N | ND | Y(4) | 148 | 148 | 610102700-017-G | - | RES,49.9 Ohm,+/-1%,1/16W,G,SMD0402 | KOA SPEER ELECTRONICS, INC. | RK73H1ETTP49R9F |  | 1 | 2 | 3 | 2 | G | R445,R448 |  |  |  |  |  |  |
|  |  |  |  |  | 148 | 610102700-012-G |  | RES,49.9 Ohm,+/-1%,1/16W,G,SMD0402 | WALSIN TECHNOLOGY CORPORATION | WR04X49R9FTL |  | 1 | 2 | 3 |  | G |  |  |  |  |  |  |  |
|  |  |  |  |  | 148 | 610102700-011-G |  | RES,49.9 Ohm,+/-1%,1/16W,G,SMD0402 | YAGEO CORPORATION COMPONENT | RC0402FR-0749R9L | EVT | 1 | 2 | 3 |  | G |  |  |  |  |  |  |  |
|  |  |  |  |  | 148 | 610102700-044-G |  | RES,49.9 Ohm,+/-1%,1/16W,G,SMD0402 | TA-I TECHNOLOGY CO., LTD. | RM04FTN49R9 |  | 1 | 2 | 3 |  | G |  |  |  |  |  |  |  |
|  |  |  |  |  | 148 | 610102700-029-G |  | RES,49.9 Ohm,+/-1%,1/16W,G,SMD0402 | VISHAY ENTER TECHNO LOGY.INC | CRCW040249R9FKED |  | 1 | 2 | 3 |  | G |  |  |  |  |  |  |  |
|  |  |  |  |  | 148 | 610102700-024-G |  | RES,49.9 Ohm,+/-1%,1/16W,G,SMD0402 | PANASONIC INDUSTRIAL CO.,LTD. | ERJ2RKF49R9X |  | 1 | 2 | 3 |  | G |  |  |  |  |  |  |  |
| Multi | N | ND | Y(4) | 149 | 149 | 610115J00-017-G | - | RES,33 Ohm,+/-1%,1/16W,G,SMD0402 | KOA SPEER ELECTRONICS, INC. | RK73H1ETTP33R0F |  | 1 | 2 | 3 | 2 | G | R446,R447 |  |  |  |  |  |  |
|  |  |  |  |  | 149 | 610115J00-012-G |  | RES,33 Ohm,+/-1%,1/16W,G,SMD0402 | WALSIN TECHNOLOGY CORPORATION | WR04X33R0FTL | EVT | 1 | 2 | 3 |  | G |  |  |  |  |  |  |  |
|  |  |  |  |  | 149 | 610115J00-011-G |  | RES,33 Ohm,+/-1%,1/16W,G,SMD0402 | YAGEO CORPORATION COMPONENT | RC0402FR-0733RL |  | 1 | 2 | 3 |  | G |  |  |  |  |  |  |  |
|  |  |  |  |  | 149 | 610115J00-044-G |  | RES,33 Ohm,+/-1%,1/16W,G,SMD0402 | TA-I TECHNOLOGY CO., LTD. | RM04FTN33R0 |  | 1 | 2 | 3 |  | G |  |  |  |  |  |  |  |
|  |  |  |  |  | 149 | 610115J00-024-G |  | RES,33 Ohm,+/-1%,1/16W,G,SMD0402 | PANASONIC INDUSTRIAL CO.,LTD. | ERJ2RKF33R0X |  | 1 | 2 | 3 |  | G |  |  |  |  |  |  |  |
| Multi | ND | ND | Y(4) | 150 | 150 | 61011T800-017-G | - | RES,240 Ohm,+/-1%,1/16W,G,SMD0402 | KOA SPEER ELECTRONICS, INC. | RK73H1ETTP2400F |  | 1 | 2 | 3 | 1 | G | R454 |  |  |  |  |  |  |
|  |  |  |  |  | 150 | 61011T800-012-G |  | RES,240 Ohm,+/-1%,1/16W,G,SMD0402 | WALSIN TECHNOLOGY CORPORATION | WR04X2400FTL | EVT | 1 | 2 | 3 |  | G |  |  |  |  |  |  |  |
|  |  |  |  |  | 150 | 61011T800-011-G |  | RES,240 Ohm,+/-1%,1/16W,G,SMD0402 | YAGEO CORPORATION COMPONENT | RC0402FR-07240RL |  | 1 | 2 | 3 |  | G |  |  |  |  |  |  |  |
|  |  |  |  |  | 150 | 61011T800-044-G |  | RES,240 Ohm,+/-1%,1/16W,G,SMD0402 | TA-I TECHNOLOGY CO., LTD. | RM04FTN2400 |  | 1 | 2 | 3 |  | G |  |  |  |  |  |  |  |
| Multi | ND | ND | Y(4) | 151 | 151 | 610112500-017-G | - | RES,475 Ohm,+/-1%,1/16W,G,SMD0402 | KOA SPEER ELECTRONICS, INC. | RK73H1ETTP4750F | EVT | 1 | 2 | 3 | 1 | G | R1411 |  |  |  |  |  |  |
|  |  |  |  |  | 151 | 610112500-012-G |  | RES,475 Ohm,+/-1%,1/16W,G,SMD0402 | WALSIN TECHNOLOGY CORPORATION | WR04X4750FTL |  | 1 | 2 | 3 |  | G |  |  |  |  |  |  |  |
|  |  |  |  |  | 151 | 610112500-011-G |  | RES,475 Ohm,+/-1%,1/16W,G,SMD0402 | YAGEO CORPORATION COMPONENT | RC0402FR-07475RL |  | 1 | 2 | 3 |  | G |  |  |  |  |  |  |  |
|  |  |  |  |  | 151 | 610112500-044-G |  | RES,475 Ohm,+/-1%,1/16W,G,SMD0402 | TA-I TECHNOLOGY CO., LTD. | RM04FTN4750 |  | 1 | 2 | 3 |  | G |  |  |  |  |  |  |  |
| Multi |  |  | Y(4) | 152 | 152 | 610107L00-017-G |  | RES,1 Ohm,+/-5%,1/10W,G,SMD0603 | KOA SPEER ELECTRONICS, INC. | RK73B1JTTD1R0J |  | 1 | 2 | 3 | 1 | G | R1413 |  |  |  |  |  |  |
|  |  |  |  |  | 152 | 610107L00-011-G |  | RES,1 Ohm,+/-5%,1/10W,G,SMD0603 | YAGEO CORPORATION COMPONENT | RC0603JR-071RL | EVT | 1 | 2 | 3 |  | G |  |  |  |  |  |  |  |
|  |  |  |  |  | 152 | 610107L00-012-G |  | RES,1 Ohm,+/-5%,1/10W,G,SMD0603 | WALSIN TECHNOLOGY CORPORATION | WR06X1R0JTL |  | 1 | 2 | 3 |  | G |  |  |  |  |  |  |  |
|  |  |  |  |  | 152 | 610107L00-044-G |  | RES,1 Ohm,+/-5%,1/10W,G,SMD0603 | TA-I TECHNOLOGY CO., LTD. | RM06JTN1R0 |  | 1 | 2 | 3 |  | G |  |  |  |  |  |  |  |
| Multi | N | other | Y(4) | 153 | 153 | 610107C00-017-G | K9577 | RES,10KOhm,+/-5%,1/16W,G,SMD0402 | KOA SPEER ELECTRONICS, INC. | RK73B1ETTP103J |  | 1 | 2 | 3 | 1 | G | R1426 |  |  |  |  |  |  |
|  |  |  |  |  | 153 | 610107C00-012-G |  | RES,10KOhm,+/-5%,1/16W,G,SMD0402 | WALSIN TECHNOLOGY CORPORATION | WR04X103JTL |  | 1 | 2 | 3 |  | G |  |  |  |  |  |  |  |
|  |  |  |  |  | 153 | 610107C00-011-G |  | RES,10KOhm,+/-5%,1/16W,G,SMD0402 | YAGEO CORPORATION COMPONENT | RC0402JR-0710KL | EVT | 1 | 2 | 3 |  | G |  |  |  |  |  |  |  |
|  |  |  |  |  | 153 | 610107C00-044-G |  | RES,10KOhm,+/-5%,1/16W,G,SMD0402 | TA-I TECHNOLOGY CO., LTD. | RM04JTN103 |  | 1 | 2 | 3 |  | G |  |  |  |  |  |  |  |
|  |  |  |  |  | 153 | 610107C00-024-G |  | RES,10KOhm,+/-5%,1/16W,G,SMD0402 | PANASONIC INDUSTRIAL CO.,LTD. | ERJ2GEJ103X |  | 1 | 2 | 3 |  | G |  |  |  |  |  |  |  |
|  |  |  |  |  | 153 | 610107C00-029-G |  | RES,10KOhm,+/-5%,1/16W,G,SMD0402 | VISHAY ENTER TECHNO LOGY.INC | CRCW040210K0JNED |  | 1 | 2 | 3 |  | G |  |  |  |  |  |  |  |
| Multi | N | ND | Y(4) | 154 | 154 | 610118100-017-G | - | RES,1.4KOhm,+/-1%,1/16W,G,SMD0402 | KOA SPEER ELECTRONICS, INC. | RK73H1ETTP1401F |  | 1 | 2 | 3 | 4 | G | R1529,R1530,R1531,R1532 |  |  |  |  |  |  |
|  |  |  |  |  | 154 | 610118100-012-G |  | RES,1.4KOhm,+/-1%,1/16W,G,SMD0402 | WALSIN TECHNOLOGY CORPORATION | WR04X1401FTL |  | 1 | 2 | 3 |  | G |  |  |  |  |  |  |  |
|  |  |  |  |  | 154 | 610118100-011-G |  | RES,1.4KOhm,+/-1%,1/16W,G,SMD0402 | YAGEO CORPORATION COMPONENT | RC0402FR-071K4L |  | 1 | 2 | 3 |  | G |  |  |  |  |  |  |  |
|  |  |  |  |  | 154 | 610118100-044-G |  | RES,1.4KOhm,+/-1%,1/16W,G,SMD0402 | TA-I TECHNOLOGY CO., LTD | RM04FTN1401 |  | 1 | 2 | 3 |  | G |  |  |  |  |  |  |  |
|  |  |  |  |  | 154 | 610118100-024-G |  | RES,1.4KOhm,+/-1%,1/16W,G,SMD0402 | PANASONIC INDUSTRIAL CO.,LTD. | ERJ2RKF1401X |  | 1 | 2 | 3 |  | G |  |  |  |  |  |  |  |
| Single | ND |  | Y(1) | 155 | 155 | 21050LA00-217-G |  | IC,IDT,5V41234NLGI8,G,VFQFPN-16,SMD | INTEGRATED DEVICE TECHNOLOGY | 5V41234NLGI8 | EVT | 1 | 2 | 3 | 1 | G | U_CLKGEN |  |  |  |  |  |  |
| Multi | N |  | N | 156 | 156 | 41050R700-396-G |  | Flash,S29GL128S10TFIV20,2.7~3.6V,128M,CFI,G,TSOP-56,SMD | SPANSION INTERNATIONAL LLC | S29GL128S10TFIV20 | EVT | 1 |  |  | 1 | G | U_EXP_FLASH1 |  |  |  |  |  |  |
|  |  |  |  |  | 156 | 410515T00-216-G |  | Flash,MT28EW128ABA1LJS-0SIT,2.7V~3.6V,128M,CFI,G,TSOP-56,SMD | MICRON TECHNOLOGY, INC. | MT28EW128ABA1LJS-0SIT |  |  | 2 |  |  | G |  |  |  |  |  |  |  |
|  |  |  |  |  | 156 | 41050UE00-233-G |  | Flash,MX29GL128FDT2I-11G,2.7~3.6V,128M,CFI,G,TSOP-56,SMD | MACRONIX INTERNATIONAL CO.,LTD. | MX29GL128FDT2I-11G |  |  |  | 3 |  | G |  |  |  |  |  |  |  |
| Multi | ND |  | Y(3) | 157 | 157 | 41040DK00-191-G |  | EEPROM,AT24C04C-SSHM-T,1.7~5.5V,4K,2-wire,G,SOIC-8,SMD | ATMEL CORPORATION | AT24C04C-SSHM-T | EVT | 1 |  |  | 1 | G | U_EXP_FRU1 |  |  |  |  |  |  |
|  |  |  |  |  | 157 | 41040C200-223-G |  | EEPROM,CAT24C04WI-GT3,1.8~5.5V,4K,I2C,G,SOIC-8,SMD | ON SEMICONDUCTOR CORP | CAT24C04WI-GT3 |  |  | 2 |  |  | G |  |  |  |  |  |  |  |
|  |  |  |  |  | 157 | 410405J00-214-G |  | EEPROM,M24C04-RMN6TP,1.8~5.5V,4K,2-Wire Serial,G,SO-8,SMD | STMICROELECTRONICS | M24C04-RMN6TP |  |  |  | 3 |  | G |  |  |  |  |  |  |  |
| Multi | ND |  | N | 158 | 158 | 41040HW00-191-G |  | EEPROM,AT24C02D-SSHM-T,1.7~3.6V,2K,I2C,G,SOIC-8,SMD | ATMEL CORPORATION | AT24C02D-SSHM-T |  | 1 |  |  | 1 | G | U_EXP_FRU2 |  |  |  |  |  |  |
|  |  |  |  |  | 158 | 410401W00-214-G |  | EEPROM,M24C02-WMN6TP,2.5~5.5V,256*8,I2C,G,SOIC-8,SMD | ST MICRO ELECTRONICS,INC | M24C02-WMN6TP |  |  | 2 |  |  | G |  |  |  |  |  |  |  |
|  |  |  |  |  | 158 | 41040J500-232-G |  | EEPROM,24AA024T-I/SN,1.7V~5.5V,2K,I2C,G,SOIC-8,SMD | MICROCHIP TECHNOLOGY INC | 24AA024T-I/SN |  |  |  | 3 |  | G |  |  |  |  |  |  |  |
| Multi | N | ND | N | 159 | 159 | 420103500-18R-G |  | SRAM,MR0D08BMA45R,3.3V,128K*8,G,FBGA-48,SMD | Everspin Technologies, Inc. | MR0D08BMA45R | EVT | 1 |  | 3 | 1 | G | U_EXP_NVSRAM1 |  |  |  |  |  |  |
|  |  |  |  |  | 159 | 420103G00-244-G | - | SRAM,CY14V101LA-BA45XIT,3.0~3.6V,1M,G,FBGA-48,SMD | CYPRESS SEMICONDUCTOR CORP | CY14V101LA-BA45XIT |  |  | 2 |  |  | G |  |  |  |  |  |  |  |
| Multi | ND | ND | N | 160 | 160 | 311004800-031-G | - | IC,Translator,PCA9617ADPJ,0.8~5.5V,2.2~5.5V,G,TSSOP-8,SMD | NXP SEMICONDUCTORS | PCA9617ADPJ |  |  | 2 |  | 2 | G | U8,U_I2C_RE1 |  |  |  |  |  |  |
|  |  |  |  |  | 160 | 311004V00-223-G |  | Logic IC,Translator,PCA9617ADMR2G,Vcca=0.8V~5.5V,Vccb=2.2V~5.5V,102ns,Micro8,8P,G | ON SEMICONDUCTOR CORP | PCA9617ADMR2G | EVT | 1 |  | 3 |  | G |  |  |  |  |  |  |  |
| Single | ND |  | N | 161 | 161 | 210826W00-283-G |  | IC,BROADCOM,PEX9797-AA80BCG,AA,G,FCBGA-1156,SMD | BROADCOM SINGAPORE PTE LTD. | SS14-0B00-00 | EVT | 1 | 2 | 3 | 1 | G | U_PEX_SW1 |  |  |  |  |  |  |
| Multi | N | ND | Y(3) | 162 | 162 | 310101400-031-G | - | IC,Gate&Inverter,74LVC1G08GW,1.65~5.5V,G,SOT353-5,SMD | NXP SEMICONDUCTORS | 74LVC1G08GW | EVT | 1 |  |  | 2 | G | U2,U108 |  |  |  |  |  |  |
|  |  |  |  |  | 162 | 310103J00-223-G |  | IC,Gate&Inverter,NL17SZ08DFT2G,1.65~5.5V,G,SOT353-5,SMD | ON SEMICONDUCTOR CORP | NL17SZ08DFT2G |  |  | 2 |  |  | G |  |  |  |  |  |  |  |
|  |  |  |  |  | 162 | 31010J400-131-G |  | IC,Gate&Inverter,TC7SZ08FU,1.8~5.5V,G,SSOP-5,SMD | TOSHIBA ELECTRONICS ASIA LTD | TC7SZ08FU |  |  |  | 3 |  | G |  |  |  |  |  |  |  |
| Single | ND |  | N | 163 | 163 | 210828A00-GUW-G |  | IC,AVAGO,SX00-0B00-00,G,fpBGA-1197,SMD | AVAGO TECHNOLOGIES INTERNATION/AGILENT SEMICONDUCTOR | SX00-0B00-00 | EVT | 1 | 2 | 3 | 1 | G | U3 |  |  |  |  |  |  |
| Single | ND | ND | N | 164 | 164 | 32020WJ00-183-G | - | IC,Power Controller,TPS3808G01DBVR,G,SOT23-6,SMD | TEXAS INSTRUMENTS | TPS3808G01DBVR | EVT | 1 | 2 | 3 | 1 | G | U4 |  |  |  |  |  |  |
| Multi | Y |  | N | 165 | 165 | 32022FF00-173-G |  | IC,Power Controller,MAX6315US29D1+T,G,SOT-143-4,SMD | MAXIM INTEGRATED PRODUCTS, INC. | MAX6315US29D1+T | EVT | 1 |  | 3 | 1 | G | U6 |  |  |  |  |  |  |
|  |  |  |  |  | 165 | 32022NH00-252-G |  | IC,Power Controller,PT7M6315US29D1TBEX,G,SOT143-4,SMD | PERICOM SEMICONDUCTOR CORP | PT7M6315US29D1TBEX |  |  | 2 |  |  | G |  |  |  |  |  |  |  |
| Multi | ND | ND | Y(1) | 166 | 166 | 41040G200-214-G |  | EEPROM,M95256-RMN6TP,1.8~5.5V,256K,SPI,G,SO-8,SMD | ST MICRO ELECTRONICS,INC | M95256-RMN6TP | EVT | 1 |  |  | 2 | G | U9,U117 |  |  |  |  |  |  |
|  |  |  |  |  | 166 | 410409700-191-G | - | EEPROM,AT25256B-SSHL-T,1.8~5.5V,256K,SPI,G,SOIC-8,SMD | ATMEL CORPORATION | AT25256B-SSHL-T |  |  | 2 |  |  | G |  |  |  |  |  |  |  |
|  |  |  |  |  | 166 | 410405T00-223-G |  | EEPROM,CAT25256VI-GT3,1.8~5.5V,256K,SPI,G,SOIC-8,SMD | ON SEMICONDUCTOR CORP | CAT25256VI-GT3 |  |  |  | 3 |  | G |  |  |  |  |  |  |  |
|  |  |  |  |  | 166 | 41040B800-232-G |  | EEPROM,25AA256T-I/SN,1.8~5.5V,256K,SPI,G,SOIC-8,SMD | MICROCHIP TECHNOLOGY INC | 25AA256T-I/SN |  |  |  |  |  | G |  |  |  |  |  |  |  |
| Multi | ND | ND | N | 167 | 167 | 310408900-217-G | - | IC,Switch,74CBTLV3257PGG8,2.3~3.6V,G,TSSOP-16,SMD | INTEGRATED DEVICE TECHNOLOGY | 74CBTLV3257PGG8 |  | 1 |  | 3 | 1 | G | U27 |  |  |  |  |  |  |
|  |  |  |  |  | 167 | 310405F00-252-G |  | Logic IC,Multiplexer,PI3B3257LEX,2.97V~3.63V,0.25ns,TSSOP,16P,G | PERICOM SEMICONDUCTOR CORP | PI3B3257LEX |  |  | 2 |  |  | G |  |  |  |  |  |  |  |
| Multi | ND | ND | Y(3) | 168 | 168 | 310502800-031-G |  | IC,Buffer,74LVC1G07GW,1.65~5.5V,G,SOT353-5,SMD | NXP SEMICONDUCTORS | 74LVC1G07GW |  |  | 2 |  | 2 | G | U107,U110 |  |  |  |  |  |  |
|  |  |  |  |  | 168 | 31050CU00-131-G |  | IC,Buffer,TC7SZ07FU,1.65~5.5V,G,SSOP-5,SMD | TOSHIBA ELECTRONICS ASIA LTD | TC7SZ07FU | EVT | 1 |  |  |  | G |  |  |  |  |  |  |  |
|  |  |  |  |  | 168 | 310502C00-223-G |  | IC,Buffer,NL17SZ07DFT2G,1.65~5.50V,G,SC-88A/SOT-353-5,SMD | ON SEMICONDUCTOR CORP | NL17SZ07DFT2G | EVT |  |  | 3 |  | G |  |  |  |  |  |  |  |
| Multi | ND |  | N | 169 | 169 | 310504B00-031-G |  | IC,Buffer,74LVC1G17GW,1.65~5.5V,G,SOT353-5,SMD | NXP SEMICONDUCTORS | 74LVC1G17GW |  |  | 2 |  | 1 | G | U109 |  |  |  |  |  |  |
|  |  |  |  |  | 169 | 310507Q00-223-G |  | Logic IC,Buffer,NL17SZ17DFT2G,1.65V~5.5V,15ns,SC-88A/SOT-353,5P,G | ON SEMICONDUCTOR CORP | NL17SZ17DFT2G | EVT | 1 |  |  |  | G |  |  |  |  |  |  |  |
|  |  |  |  |  | 169 | 31050BH00-131-G |  | IC,Buffer,TC7SZ17FU,1.65~5.5V,G,SSOP-5,SMD | TOSHIBA ELECTRONICS ASIA LTD | TC7SZ17FU |  |  |  | 3 |  | G |  |  |  |  |  |  |  |
| Single | ND |  | N | 170 | 170 | 710124Y00-100-G |  | XTAL,25MHz,+/-20ppm,20pF,G,SMD | TXC CORPORATION | 7M25020015 | EVT | 1 | 2 | 3 | 1 | G | X1 |  |  |  |  |  |  |
| Multi | N | ND | N | 171 | 171 | 71020C700-621-G | - | OSC,150MHz,+/-50ppm,3.3V,50ohm,G,SMD | FOX ELECTRONICS INC | 774-150-8 | EVT | 1 |  |  | 1 | G | Y1 |  |  |  |  |  |  |
|  |  |  |  |  | 171 | 71020C800-162-G |  | OSC,150MHz,+/-50ppm,3.3V,50 Ohm,G,SMD | EPSON ELECTRONICS AMERICA,INC. | EG-2102CA 150.0000M-PGPAB |  |  | 2 |  |  | G |  |  |  |  |  |  |  |
|  |  |  |  |  | 171 | 71020C900-252-G |  | OSC,150MHz,+/-50ppm,3.3V,50ohm,G,SMD | PERICOM SEMICONDUCTOR CORP | S2692-150.0000(T) |  |  |  | 3 |  | G |  |  |  |  |  |  |  |
|  |  |  |  |  | 171 | 71020NF00-16G-G |  | OSC,150MHz,+/-50ppm,3.3V,,,-20_x0003_~70_x0003_,SMD,G | SiTime Corporation | SIT9120AC-1D3-33E150.000000T |  |  |  |  |  | G |  |  |  |  |  |  |  |
| Multi | Y |  | N | 172 | 172 | 340718A00-245-G |  | CONN,SAS,V/T,0.6mm,30u,G,SMD-74 | AMPHENOL SHANGHAI CORP. | U10-B074-250T | EVT | 1 |  | 3 | 12 | G | J_PCIE_OUT1,J_PCIE_IN1,J_PCIE_OUT2,J_PCIE_IN2,J_PCIE_OUT3,J_PCIE_OUT4,J4,J_PCIE_OUT5,J5,J_PCIE_OUT6,J6,J_PCIE_OUT7 |  |  |  |  |  |  |
|  |  |  |  |  | 172 | U10-B274-250T |  | CONN,SAS,V/T,0.6mm,30u,G,SMD-74 | AMPHENOL SHANGHAI CORP. | U10-B274-250T |  |  | 2 |  |  | G |  |  |  |  |  |  |  |
| Single | ND |  | N | 173 | 173 | 34066Q200-317-G |  | CONN,Header,Power,2X8,V/T,Bla,3mm,G,DIP-16 | MOLEX INCORPORATED | 43045-1627 |  | 1 | 2 | 3 | 1 | G | J_PWR_BP |  |  |  |  |  |  |
| Single | ND |  | N | 174 | 174 | 340636700-600-G |  | CONN,Header,Power,2X8,V/T,Whi,4.2mm,G,DIP-16 | FOXCONN TECHNOLOGY CO.,LTD. | HM3508E-HP1 |  | 1 | 2 | 3 | 1 | G | J_PWR_IN |  |  |  |  |  |  |
| Single | Y |  | N | 175 | 175 | 340716800-245-G |  | CONN,SAS,V/T,Bla,0.75mm,30u,G,SMD-72 | AMPHENOL SHANGHAI CORP. | G40H4232212HR | EVT | 1 | 2 | 3 | 1 | G | J_SAS_IN1 |  |  |  |  |  |  |
| Single | Y | 1 | N | 176 | 176 | 340626400-600-G |  | CONN,Header,Shrouded,1X4,V/T,1mm,Ivo,G,SMD-4 | FOXCONN TECHNOLOGY CO.,LTD. | HS6104E | EVT | 1 | 2 | 3 | 2 | G | J_UART1,J_SMART1 |  |  |  |  |  |  |
| Single | ND |  | N | 177 | 177 | 3406ALW00-317-G |  | CONN,Header,Shrouded,2X5,V/T,Bla,2mm,30u,G,SMD-10 | MOLEX INCORPORATED | 87832-5423 | EVT | 1 | 2 | 3 | 1 | G | J3 |  |  |  |  |  |  |
| Single | ND |  | N | 178 | 178 | 34045GE00-GRS-G |  | CONN,SPI FLASH SOCKET,Bla,1.27mm,15u,G,SMD-8 | LOTES CO LTD | ASPI0001-P002A | EVT | 1 | 2 | 3 | 1 | G | U10 |  |  |  |  |  |  |
